FILE_TYPE = MACRO_DRAWING;
SET COLOR_WIRE YELLOW;
SET COLOR_PROP MONO;
SET COLOR_DOT WHITE;
SET COLOR_ARC YELLOW;
SET COLOR_BODY GREEN;
SET COLOR_NOTE MONO;
SET PROP_DISPLAY VALUE;
SET PAGE_NUMBER P202;
FORCEADD OFFPAGE..2
(-1400 4750);
FORCEPROP 2 LAST $XR0 201 
J 0
(-1211 4750);
DISPLAY 0.638298 (-1211 4750);
PAINT MONO (-1211 4750);
FORCEPROP 2 LAST ROOM PVCCIN_CPU0_PWR_VR
J 0
(-1800 4825);
DISPLAY 1.936170 (-1800 4825);
PAINT ORANGE (-1800 4825);
DISPLAY INVISIBLE (-1800 4825);
FORCEPROP 2 LAST CDS_LIB mstr_standard
J 2
(-1400 4750);
DISPLAY 1.936170 (-1400 4750);
PAINT ORANGE (-1400 4750);
DISPLAY INVISIBLE (-1400 4750);
FORCEPROP 2 LAST PATH I1
J 0
(-1195 4800);
DISPLAY 1.021277 (-1195 4800);
PAINT ORANGE (-1195 4800);
DISPLAY INVISIBLE (-1195 4800);
FORCEPROP 2 LAST BOM_COST PROC_VRD_VCCIN_CPU0
J 0
(-1200 4800);
DISPLAY 1.446809 (-1200 4800);
PAINT MONO (-1200 4800);
DISPLAY INVISIBLE (-1200 4800);
FORCEPROP 1 LAST OFFPAGE TRUE
J 0
(-1075 4625);
DISPLAY 1.723404 (-1075 4625);
PAINT GREEN (-1075 4625);
DISPLAY INVISIBLE (-1075 4625);
FORCEPROP 1 LAST COMMENT_BODY TRUE
J 0
(-1445 4655);
DISPLAY 1.723404 (-1445 4655);
PAINT GREEN (-1445 4655);
DISPLAY INVISIBLE (-1445 4655);
FORCEADD OFFPAGE..2
(-1725 2100);
FORCEPROP 2 LAST $XR0 201 
J 0
(-1536 2100);
DISPLAY 0.638298 (-1536 2100);
PAINT MONO (-1536 2100);
FORCEPROP 2 LAST ROOM PVCCIN_CPU0_PWR_VR
J 0
(-2125 2175);
DISPLAY 1.936170 (-2125 2175);
PAINT ORANGE (-2125 2175);
DISPLAY INVISIBLE (-2125 2175);
FORCEPROP 2 LAST CDS_LIB mstr_standard
J 0
(-1725 2100);
PAINT ORANGE (-1725 2100);
DISPLAY INVISIBLE (-1725 2100);
FORCEPROP 2 LAST PATH I10
J 0
(-1545 2175);
DISPLAY 1.021277 (-1545 2175);
PAINT ORANGE (-1545 2175);
DISPLAY INVISIBLE (-1545 2175);
FORCEPROP 2 LAST BOM_COST PROC_VRD_VCCIN_CPU0
J 0
(-1525 2150);
DISPLAY 1.446809 (-1525 2150);
PAINT MONO (-1525 2150);
DISPLAY INVISIBLE (-1525 2150);
FORCEPROP 1 LAST OFFPAGE TRUE
J 0
(-1400 1975);
DISPLAY 1.723404 (-1400 1975);
PAINT GREEN (-1400 1975);
DISPLAY INVISIBLE (-1400 1975);
FORCEPROP 1 LAST COMMENT_BODY TRUE
J 0
(-1770 2005);
DISPLAY 1.723404 (-1770 2005);
PAINT GREEN (-1770 2005);
DISPLAY INVISIBLE (-1770 2005);
FORCEADD RES..1
(-5025 3575);
FORCEPROP 1 LAST MATERIAL CHIP
J 0
(-4750 3475);
DISPLAY 0.617021 (-4750 3475);
PAINT SKYBLUE (-4750 3475);
FORCEPROP 1 LAST WATTAGE 1/10W
J 0
(-4900 3425);
DISPLAY 0.617021 (-4900 3425);
PAINT SKYBLUE (-4900 3425);
FORCEPROP 1 LAST LOCATION RT1
J 0
(-5050 3425);
DISPLAY 0.617021 (-5050 3425);
PAINT AQUA (-5050 3425);
FORCEPROP 1 LASTPIN (-5125 3575) $PN 1
J 0
(-5113 3587);
DISPLAY 0.787234 (-5113 3587);
PAINT ORANGE (-5113 3587);
FORCEPROP 1 LASTPIN (-4925 3575) $PN 2
J 0
(-4963 3587);
DISPLAY 0.787234 (-4963 3587);
PAINT ORANGE (-4963 3587);
FORCEPROP 1 LAST PACK_TYPE 0603
J 0
(-4950 3525);
DISPLAY 0.617021 (-4950 3525);
PAINT SKYBLUE (-4950 3525);
FORCEPROP 1 LAST VALUE 0
J 2
(-5075 3525);
DISPLAY 0.617021 (-5075 3525);
PAINT SKYBLUE (-5075 3525);
FORCEPROP 1 LAST PART_NUMBER G22178-002
J 0
(-5150 3475);
DISPLAY 0.617021 (-5150 3475);
PAINT BLUE (-5150 3475);
FORCEPROP 1 LAST TOLERANCE 5.0%
J 0
(-4900 3475);
DISPLAY 0.617021 (-4900 3475);
PAINT SKYBLUE (-4900 3475);
FORCEPROP 0 LAST SEC 1
J 0
(-5275 3675);
DISPLAY 0.680851 (-5275 3675);
PAINT MONO (-5275 3675);
DISPLAY INVISIBLE (-5275 3675);
FORCEPROP 2 LAST SEC_TYPE 0603
J 0
(-5075 3775);
DISPLAY 1.021277 (-5075 3775);
PAINT ORANGE (-5075 3775);
DISPLAY INVISIBLE (-5075 3775);
FORCEPROP 2 LAST CDS_LIB mstr_discrete
J 0
(-5025 3575);
PAINT MONO (-5025 3575);
DISPLAY INVISIBLE (-5025 3575);
FORCEPROP 1 LAST PATH I101
J 0
(-5075 3725);
DISPLAY 0.978723 (-5075 3725);
PAINT WHITE (-5075 3725);
DISPLAY INVISIBLE (-5075 3725);
FORCEPROP 0 LAST BOM_COST NT_GBE_BASE
J 0
(-4925 3800);
DISPLAY 1.021277 (-4925 3800);
PAINT ORANGE (-4925 3800);
DISPLAY INVISIBLE (-4925 3800);
FORCEPROP 0 LAST ROOM NIC_SPRV
J 0
(-4925 3700);
DISPLAY 1.021277 (-4925 3700);
PAINT ORANGE (-4925 3700);
DISPLAY INVISIBLE (-4925 3700);
FORCEADD RES..1
(-5025 950);
FORCEPROP 1 LASTPIN (-4925 950) $PN 2
J 0
(-4963 962);
DISPLAY 0.787234 (-4963 962);
PAINT ORANGE (-4963 962);
FORCEPROP 1 LAST PART_NUMBER G22178-002
J 0
(-5150 800);
DISPLAY 0.617021 (-5150 800);
PAINT BLUE (-5150 800);
FORCEPROP 1 LAST TOLERANCE 5.0%
J 0
(-4950 850);
DISPLAY 0.617021 (-4950 850);
PAINT SKYBLUE (-4950 850);
FORCEPROP 1 LAST LOCATION RT3
J 0
(-5100 850);
DISPLAY 0.617021 (-5100 850);
PAINT AQUA (-5100 850);
FORCEPROP 1 LASTPIN (-5125 950) $PN 1
J 0
(-5113 962);
DISPLAY 0.787234 (-5113 962);
PAINT ORANGE (-5113 962);
FORCEPROP 1 LAST PACK_TYPE 0603
J 0
(-4950 900);
DISPLAY 0.617021 (-4950 900);
PAINT SKYBLUE (-4950 900);
FORCEPROP 1 LAST WATTAGE 1/10W
J 0
(-4800 850);
DISPLAY 0.617021 (-4800 850);
PAINT SKYBLUE (-4800 850);
FORCEPROP 1 LAST MATERIAL CHIP
J 0
(-4800 900);
DISPLAY 0.617021 (-4800 900);
PAINT SKYBLUE (-4800 900);
FORCEPROP 1 LAST VALUE 0
J 2
(-5075 900);
DISPLAY 0.617021 (-5075 900);
PAINT SKYBLUE (-5075 900);
FORCEPROP 2 LAST SEC_TYPE 0603
J 0
(-5075 1150);
DISPLAY 1.021277 (-5075 1150);
PAINT ORANGE (-5075 1150);
DISPLAY INVISIBLE (-5075 1150);
FORCEPROP 0 LAST SEC 1
J 0
(-5275 1050);
DISPLAY 0.680851 (-5275 1050);
PAINT MONO (-5275 1050);
DISPLAY INVISIBLE (-5275 1050);
FORCEPROP 2 LAST CDS_LIB mstr_discrete
J 0
(-5025 950);
PAINT MONO (-5025 950);
DISPLAY INVISIBLE (-5025 950);
FORCEPROP 1 LAST PATH I102
J 0
(-5075 1100);
DISPLAY 0.978723 (-5075 1100);
PAINT WHITE (-5075 1100);
DISPLAY INVISIBLE (-5075 1100);
FORCEPROP 0 LAST BOM_COST NT_GBE_BASE
J 0
(-4925 1175);
DISPLAY 1.021277 (-4925 1175);
PAINT ORANGE (-4925 1175);
DISPLAY INVISIBLE (-4925 1175);
FORCEPROP 0 LAST ROOM NIC_SPRV
J 0
(-4925 1075);
DISPLAY 1.021277 (-4925 1075);
PAINT ORANGE (-4925 1075);
DISPLAY INVISIBLE (-4925 1075);
FORCEADD RES..1
(-5550 4625);
FORCEPROP 1 LAST VALUE 0.0
J 2
(-5650 4525);
DISPLAY 0.617021 (-5650 4525);
PAINT SKYBLUE (-5650 4525);
FORCEPROP 1 LAST TOLERANCE 5%
J 0
(-5600 4525);
DISPLAY 0.617021 (-5600 4525);
PAINT SKYBLUE (-5600 4525);
FORCEPROP 1 LAST PART_NUMBER G21497-005
J 0
(-5675 4575);
DISPLAY 0.617021 (-5675 4575);
PAINT BLUE (-5675 4575);
FORCEPROP 1 LASTPIN (-5650 4625) $PN 1
J 0
(-5638 4637);
DISPLAY 0.617021 (-5638 4637);
PAINT WHITE (-5638 4637);
FORCEPROP 1 LAST LOCATION R6R2
J 0
(-5650 4675);
DISPLAY 0.617021 (-5650 4675);
PAINT AQUA (-5650 4675);
FORCEPROP 1 LASTPIN (-5450 4625) $PN 2
J 0
(-5488 4637);
DISPLAY 0.617021 (-5488 4637);
PAINT WHITE (-5488 4637);
FORCEPROP 1 LAST WATTAGE 1/16W
J 0
(-5350 4650);
DISPLAY 0.638298 (-5350 4650);
PAINT SKYBLUE (-5350 4650);
FORCEPROP 1 LAST MATERIAL CHIP
J 0
(-5350 4550);
DISPLAY 0.638298 (-5350 4550);
PAINT SKYBLUE (-5350 4550);
FORCEPROP 1 LAST PACK_TYPE 0402
J 0
(-5475 4525);
DISPLAY 0.617021 (-5475 4525);
PAINT SKYBLUE (-5475 4525);
FORCEPROP 2 LAST CDS_LOCATION R6R2
J 0
(-6025 4625);
DISPLAY 0.617021 (-6025 4625);
PAINT AQUA (-6025 4625);
DISPLAY INVISIBLE (-6025 4625);
FORCEPROP 0 LAST CDS_SEC 1
J 0
(-5250 4675);
PAINT MONO (-5250 4675);
DISPLAY INVISIBLE (-5250 4675);
FORCEPROP 2 LAST ROOM CPU0
J 0
(-5600 4775);
PAINT PEACH (-5600 4775);
DISPLAY INVISIBLE (-5600 4775);
FORCEPROP 2 LAST SEC 1
J 0
(-5600 4850);
DISPLAY 0.680851 (-5600 4850);
PAINT MONO (-5600 4850);
DISPLAY INVISIBLE (-5600 4850);
FORCEPROP 2 LAST SEC_TYPE 0402
J 0
(-5600 4850);
DISPLAY 1.021277 (-5600 4850);
PAINT ORANGE (-5600 4850);
DISPLAY INVISIBLE (-5600 4850);
FORCEPROP 2 LAST CDS_LIB mstr_discrete
J 0
(-5550 4625);
DISPLAY 1.340426 (-5550 4625);
PAINT ORANGE (-5550 4625);
DISPLAY INVISIBLE (-5550 4625);
FORCEPROP 2 LAST BOM_COST PROC_SIDEBAND
J 0
(-5550 4625);
PAINT MONO (-5550 4625);
DISPLAY INVISIBLE (-5550 4625);
FORCEPROP 1 LAST PATH I107
J 0
(-5600 4775);
DISPLAY 0.978723 (-5600 4775);
PAINT WHITE (-5600 4775);
DISPLAY INVISIBLE (-5600 4775);
FORCEADD RES..1
(-5625 1975);
FORCEPROP 1 LAST VALUE 0.0
J 2
(-5700 1875);
DISPLAY 0.617021 (-5700 1875);
PAINT SKYBLUE (-5700 1875);
FORCEPROP 1 LAST PACK_TYPE 0402
J 0
(-5550 1875);
DISPLAY 0.617021 (-5550 1875);
PAINT SKYBLUE (-5550 1875);
FORCEPROP 1 LASTPIN (-5525 1975) $PN 2
J 0
(-5563 1987);
DISPLAY 0.617021 (-5563 1987);
PAINT WHITE (-5563 1987);
FORCEPROP 1 LAST LOCATION R6R6
J 0
(-5725 2025);
DISPLAY 0.617021 (-5725 2025);
PAINT AQUA (-5725 2025);
FORCEPROP 1 LASTPIN (-5725 1975) $PN 1
J 0
(-5713 1987);
DISPLAY 0.617021 (-5713 1987);
PAINT WHITE (-5713 1987);
FORCEPROP 1 LAST PART_NUMBER G21497-005
J 0
(-5750 1925);
DISPLAY 0.617021 (-5750 1925);
PAINT BLUE (-5750 1925);
FORCEPROP 1 LAST TOLERANCE 5%
J 0
(-5675 1875);
DISPLAY 0.617021 (-5675 1875);
PAINT SKYBLUE (-5675 1875);
FORCEPROP 1 LAST WATTAGE 1/16W
J 0
(-5425 2000);
DISPLAY 0.638298 (-5425 2000);
PAINT SKYBLUE (-5425 2000);
FORCEPROP 1 LAST MATERIAL CHIP
J 0
(-5400 1875);
DISPLAY 0.638298 (-5400 1875);
PAINT SKYBLUE (-5400 1875);
FORCEPROP 2 LAST CDS_LOCATION R6R6
J 0
(-6100 1975);
DISPLAY 0.617021 (-6100 1975);
PAINT AQUA (-6100 1975);
DISPLAY INVISIBLE (-6100 1975);
FORCEPROP 2 LAST BOM_COST PROC_SIDEBAND
J 0
(-5625 1975);
PAINT MONO (-5625 1975);
DISPLAY INVISIBLE (-5625 1975);
FORCEPROP 2 LAST CDS_LIB mstr_discrete
J 0
(-5625 1975);
DISPLAY 1.340426 (-5625 1975);
PAINT ORANGE (-5625 1975);
DISPLAY INVISIBLE (-5625 1975);
FORCEPROP 2 LAST SEC_TYPE 0402
J 0
(-5675 2200);
DISPLAY 1.021277 (-5675 2200);
PAINT ORANGE (-5675 2200);
DISPLAY INVISIBLE (-5675 2200);
FORCEPROP 2 LAST SEC 1
J 0
(-5675 2200);
DISPLAY 0.680851 (-5675 2200);
PAINT MONO (-5675 2200);
DISPLAY INVISIBLE (-5675 2200);
FORCEPROP 2 LAST ROOM CPU0
J 0
(-5675 2125);
PAINT PEACH (-5675 2125);
DISPLAY INVISIBLE (-5675 2125);
FORCEPROP 0 LAST CDS_SEC 1
J 0
(-5325 2025);
PAINT MONO (-5325 2025);
DISPLAY INVISIBLE (-5325 2025);
FORCEPROP 1 LAST PATH I108
J 0
(-5675 2125);
DISPLAY 0.978723 (-5675 2125);
PAINT WHITE (-5675 2125);
DISPLAY INVISIBLE (-5675 2125);
FORCEADD IND-120NH-30-GP..1
R 1
(-1700 3525);
FORCEPROP 2 LAST TYPE IRMS=66A@DELTA_T<40C
J 0
(-1850 3275);
DISPLAY 0.638298 (-1850 3275);
PAINT GREEN (-1850 3275);
FORCEPROP 2 LAST PACK_SIZE DCR=0.17MOHM
J 0
(-1850 3225);
DISPLAY 0.638298 (-1850 3225);
PAINT GREEN (-1850 3225);
FORCEPROP 2 LAST RATED ISAT=94A@25C
J 0
(-1850 3325);
DISPLAY 0.638298 (-1850 3325);
PAINT GREEN (-1850 3325);
FORCEPROP 2 LAST ATTRIBUTE 120NH
J 0
(-1850 3375);
DISPLAY 0.638298 (-1850 3375);
PAINT GREEN (-1850 3375);
FORCEPROP 1 LAST LOCATION L4E1
J 0
(-1850 3575);
DISPLAY 0.617021 (-1850 3575);
PAINT GREEN (-1850 3575);
FORCEPROP 2 LASTPIN (-1850 3500) $PN 1
J 2
(-1860 3510);
DISPLAY 0.808511 (-1860 3510);
PAINT ORANGE (-1860 3510);
FORCEPROP 1 LAST VALUE IND-120NH-30-GP
J 0
(-1850 3425);
DISPLAY 0.617021 (-1850 3425);
PAINT GREEN (-1850 3425);
FORCEPROP 2 LASTPIN (-1550 3500) $PN 2
J 0
(-1540 3510);
DISPLAY 0.808511 (-1540 3510);
PAINT ORANGE (-1540 3510);
FORCEPROP 1 LAST PART_NUMBER 068.1202N.M001
R 1
J 0
(-1700 3525);
DISPLAY 0.617021 (-1700 3525);
PAINT GREEN (-1700 3525);
DISPLAY INVISIBLE (-1700 3525);
FORCEPROP 2 LAST CDS_LIB w_hdl
R 1
J 0
(-1700 3525);
PAINT MONO (-1700 3525);
DISPLAY INVISIBLE (-1700 3525);
FORCEPROP 1 LAST CDS_LMAN_SYM_OUTLINE -75,100,75,-100
R 1
J 0
(-1700 3525);
DISPLAY 0.468085 (-1700 3525);
PAINT GREEN (-1700 3525);
DISPLAY INVISIBLE (-1700 3525);
FORCEPROP 2 LAST SEC_TYPE DISCRET-GB2
J 0
(-1825 3600);
DISPLAY 1.021277 (-1825 3600);
PAINT ORANGE (-1825 3600);
DISPLAY INVISIBLE (-1825 3600);
FORCEPROP 2 LAST SEC 1
J 0
(-1825 3600);
DISPLAY 0.680851 (-1825 3600);
PAINT MONO (-1825 3600);
DISPLAY INVISIBLE (-1825 3600);
FORCEPROP 1 LAST PACK_TYPE DISCRET-GB2
R 1
J 0
(-1700 3525);
DISPLAY 0.617021 (-1700 3525);
PAINT GREEN (-1700 3525);
DISPLAY INVISIBLE (-1700 3525);
FORCEPROP 1 LAST PATH I109
R 1
J 0
(-1700 3525);
DISPLAY 0.617021 (-1700 3525);
PAINT GREEN (-1700 3525);
DISPLAY INVISIBLE (-1700 3525);
FORCEADD OFFPAGE..2
(-1675 1725);
FORCEPROP 2 LAST $XR0 201 
J 0
(-1486 1725);
DISPLAY 0.638298 (-1486 1725);
PAINT MONO (-1486 1725);
FORCEPROP 2 LAST ROOM PVCCIN_CPU0_PWR_VR
J 0
(-2075 1800);
DISPLAY 1.936170 (-2075 1800);
PAINT ORANGE (-2075 1800);
DISPLAY INVISIBLE (-2075 1800);
FORCEPROP 2 LAST CDS_LIB mstr_standard
J 0
(-1675 1725);
PAINT ORANGE (-1675 1725);
DISPLAY INVISIBLE (-1675 1725);
FORCEPROP 2 LAST PATH I11
J 0
(-1495 1800);
DISPLAY 1.021277 (-1495 1800);
PAINT ORANGE (-1495 1800);
DISPLAY INVISIBLE (-1495 1800);
FORCEPROP 2 LAST BOM_COST PROC_VRD_VCCIN_CPU0
J 0
(-1475 1775);
DISPLAY 1.446809 (-1475 1775);
PAINT MONO (-1475 1775);
DISPLAY INVISIBLE (-1475 1775);
FORCEPROP 1 LAST OFFPAGE TRUE
J 0
(-1350 1600);
DISPLAY 1.723404 (-1350 1600);
PAINT GREEN (-1350 1600);
DISPLAY INVISIBLE (-1350 1600);
FORCEPROP 1 LAST COMMENT_BODY TRUE
J 0
(-1720 1630);
DISPLAY 1.723404 (-1720 1630);
PAINT GREEN (-1720 1630);
DISPLAY INVISIBLE (-1720 1630);
FORCEADD IND-120NH-30-GP..1
R 1
(-1300 975);
FORCEPROP 2 LAST TYPE IRMS=66A@DELTA_T<40C
J 0
(-1450 725);
DISPLAY 0.638298 (-1450 725);
PAINT GREEN (-1450 725);
FORCEPROP 2 LAST PACK_SIZE DCR=0.17MOHM
J 0
(-1450 675);
DISPLAY 0.638298 (-1450 675);
PAINT GREEN (-1450 675);
FORCEPROP 2 LAST RATED ISAT=94A@25C
J 0
(-1450 775);
DISPLAY 0.638298 (-1450 775);
PAINT GREEN (-1450 775);
FORCEPROP 2 LAST ATTRIBUTE 120NH
J 0
(-1450 825);
DISPLAY 0.638298 (-1450 825);
PAINT GREEN (-1450 825);
FORCEPROP 1 LAST VALUE IND-120NH-30-GP
J 0
(-1450 875);
DISPLAY 0.617021 (-1450 875);
PAINT GREEN (-1450 875);
FORCEPROP 2 LASTPIN (-1150 950) $PN 2
J 0
(-1140 960);
DISPLAY 0.808511 (-1140 960);
PAINT ORANGE (-1140 960);
FORCEPROP 2 LASTPIN (-1450 950) $PN 1
J 2
(-1460 960);
DISPLAY 0.808511 (-1460 960);
PAINT ORANGE (-1460 960);
FORCEPROP 1 LAST LOCATION L4D3
J 0
(-1450 1025);
DISPLAY 0.617021 (-1450 1025);
PAINT GREEN (-1450 1025);
FORCEPROP 1 LAST PATH I110
R 1
J 0
(-1300 975);
DISPLAY 0.617021 (-1300 975);
PAINT GREEN (-1300 975);
DISPLAY INVISIBLE (-1300 975);
FORCEPROP 1 LAST PART_NUMBER 068.1202N.M001
R 1
J 0
(-1300 975);
DISPLAY 0.617021 (-1300 975);
PAINT GREEN (-1300 975);
DISPLAY INVISIBLE (-1300 975);
FORCEPROP 2 LAST CDS_LIB w_hdl
R 1
J 0
(-1300 975);
PAINT MONO (-1300 975);
DISPLAY INVISIBLE (-1300 975);
FORCEPROP 1 LAST CDS_LMAN_SYM_OUTLINE -75,100,75,-100
R 1
J 0
(-1300 975);
DISPLAY 0.468085 (-1300 975);
PAINT GREEN (-1300 975);
DISPLAY INVISIBLE (-1300 975);
FORCEPROP 2 LAST SEC_TYPE DISCRET-GB2
J 0
(-1425 1050);
DISPLAY 1.021277 (-1425 1050);
PAINT ORANGE (-1425 1050);
DISPLAY INVISIBLE (-1425 1050);
FORCEPROP 2 LAST SEC 1
J 0
(-1425 1050);
DISPLAY 0.680851 (-1425 1050);
PAINT MONO (-1425 1050);
DISPLAY INVISIBLE (-1425 1050);
FORCEPROP 1 LAST PACK_TYPE DISCRET-GB2
R 1
J 0
(-1300 975);
DISPLAY 0.617021 (-1300 975);
PAINT GREEN (-1300 975);
DISPLAY INVISIBLE (-1300 975);
FORCEADD SC1U10V2KX-4-GP..1
(-5275 1425);
FORCEPROP 2 LAST ATTRIBUTE 1UF
J 0
(-5150 1450);
DISPLAY 0.638298 (-5150 1450);
PAINT GREEN (-5150 1450);
FORCEPROP 2 LAST TOLERANCE 10%
J 0
(-5150 1400);
DISPLAY 0.638298 (-5150 1400);
PAINT GREEN (-5150 1400);
FORCEPROP 1 LAST VALUE SC1U10V2KX-4-GP
R 1
J 0
(-5175 1225);
DISPLAY 0.617021 (-5175 1225);
PAINT GREEN (-5175 1225);
FORCEPROP 2 LAST PACK_SIZE 0402
J 0
(-5150 1300);
DISPLAY 0.638298 (-5150 1300);
PAINT GREEN (-5150 1300);
FORCEPROP 2 LAST RATED 10V
J 0
(-5150 1350);
DISPLAY 0.638298 (-5150 1350);
PAINT GREEN (-5150 1350);
FORCEPROP 2 LASTPIN (-5275 1500) $PN 1
R 1
J 0
(-5285 1510);
DISPLAY 0.808511 (-5285 1510);
PAINT ORANGE (-5285 1510);
FORCEPROP 1 LAST LOCATION C4E25
J 0
(-5150 1505);
DISPLAY 0.617021 (-5150 1505);
PAINT GREEN (-5150 1505);
FORCEPROP 2 LASTPIN (-5275 1350) $PN 2
R 1
J 2
(-5285 1340);
DISPLAY 0.808511 (-5285 1340);
PAINT ORANGE (-5285 1340);
FORCEPROP 1 LAST PACK_TYPE SMD-BCG6
J 0
(-5275 1425);
DISPLAY 0.617021 (-5275 1425);
PAINT GREEN (-5275 1425);
DISPLAY INVISIBLE (-5275 1425);
FORCEPROP 2 LAST SEC 1
J 0
(-5250 1500);
DISPLAY 0.680851 (-5250 1500);
PAINT MONO (-5250 1500);
DISPLAY INVISIBLE (-5250 1500);
FORCEPROP 2 LAST SEC_TYPE SMD-BCG6
J 0
(-5250 1500);
DISPLAY 1.021277 (-5250 1500);
PAINT ORANGE (-5250 1500);
DISPLAY INVISIBLE (-5250 1500);
FORCEPROP 1 LAST PART_NUMBER 78.10523.8FL
J 0
(-5275 1425);
DISPLAY 0.617021 (-5275 1425);
PAINT GREEN (-5275 1425);
DISPLAY INVISIBLE (-5275 1425);
FORCEPROP 2 LAST CDS_LIB w_hdl
J 0
(-5275 1425);
PAINT MONO (-5275 1425);
DISPLAY INVISIBLE (-5275 1425);
FORCEPROP 1 LAST PATH I111
J 0
(-5275 1425);
DISPLAY 0.617021 (-5275 1425);
PAINT GREEN (-5275 1425);
DISPLAY INVISIBLE (-5275 1425);
FORCEPROP 1 LAST CDS_LMAN_SYM_OUTLINE -50,25,50,-25
J 0
(-5275 1425);
DISPLAY 0.468085 (-5275 1425);
PAINT GREEN (-5275 1425);
DISPLAY INVISIBLE (-5275 1425);
FORCEADD SC1U10V2KX-4-GP..1
(-5275 4075);
FORCEPROP 2 LAST RATED 10V
J 0
(-5150 4000);
DISPLAY 0.638298 (-5150 4000);
PAINT GREEN (-5150 4000);
FORCEPROP 2 LAST TOLERANCE 10%
J 0
(-5150 4050);
DISPLAY 0.638298 (-5150 4050);
PAINT GREEN (-5150 4050);
FORCEPROP 2 LAST ATTRIBUTE 1UF
J 0
(-5150 4100);
DISPLAY 0.638298 (-5150 4100);
PAINT GREEN (-5150 4100);
FORCEPROP 1 LAST LOCATION C4E6
J 0
(-5150 4155);
DISPLAY 0.617021 (-5150 4155);
PAINT GREEN (-5150 4155);
FORCEPROP 1 LAST VALUE SC1U10V2KX-4-GP
R 1
J 0
(-5175 3850);
DISPLAY 0.617021 (-5175 3850);
PAINT GREEN (-5175 3850);
FORCEPROP 2 LASTPIN (-5275 4000) $PN 2
R 1
J 2
(-5285 3990);
DISPLAY 0.808511 (-5285 3990);
PAINT ORANGE (-5285 3990);
FORCEPROP 2 LASTPIN (-5275 4150) $PN 1
R 1
J 0
(-5285 4160);
DISPLAY 0.808511 (-5285 4160);
PAINT ORANGE (-5285 4160);
FORCEPROP 2 LAST PACK_SIZE 0402
J 0
(-5150 3950);
DISPLAY 0.638298 (-5150 3950);
PAINT GREEN (-5150 3950);
FORCEPROP 1 LAST PACK_TYPE SMD-BCG6
J 0
(-5275 4075);
DISPLAY 0.617021 (-5275 4075);
PAINT GREEN (-5275 4075);
DISPLAY INVISIBLE (-5275 4075);
FORCEPROP 2 LAST SEC 1
J 0
(-5250 4150);
DISPLAY 0.680851 (-5250 4150);
PAINT MONO (-5250 4150);
DISPLAY INVISIBLE (-5250 4150);
FORCEPROP 2 LAST SEC_TYPE SMD-BCG6
J 0
(-5250 4150);
DISPLAY 1.021277 (-5250 4150);
PAINT ORANGE (-5250 4150);
DISPLAY INVISIBLE (-5250 4150);
FORCEPROP 1 LAST PART_NUMBER 78.10523.8FL
J 0
(-5275 4075);
DISPLAY 0.617021 (-5275 4075);
PAINT GREEN (-5275 4075);
DISPLAY INVISIBLE (-5275 4075);
FORCEPROP 2 LAST CDS_LIB w_hdl
J 0
(-5275 4075);
PAINT MONO (-5275 4075);
DISPLAY INVISIBLE (-5275 4075);
FORCEPROP 1 LAST PATH I112
J 0
(-5275 4075);
DISPLAY 0.617021 (-5275 4075);
PAINT GREEN (-5275 4075);
DISPLAY INVISIBLE (-5275 4075);
FORCEPROP 1 LAST CDS_LMAN_SYM_OUTLINE -50,25,50,-25
J 0
(-5275 4075);
DISPLAY 0.468085 (-5275 4075);
PAINT GREEN (-5275 4075);
DISPLAY INVISIBLE (-5275 4075);
FORCEADD 1R3F-GP..1
(-2550 2950);
FORCEPROP 0 LAST POP NOPOP
J 0
(-2525 2800);
DISPLAY 0.638298 (-2525 2800);
PAINT RED (-2525 2800);
FORCEPROP 2 LAST TOLERANCE 1%
J 0
(-2525 2950);
DISPLAY 0.638298 (-2525 2950);
PAINT GREEN (-2525 2950);
FORCEPROP 1 LAST LOCATION RT2
J 0
(-2525 3100);
DISPLAY 0.617021 (-2525 3100);
PAINT GREEN (-2525 3100);
FORCEPROP 2 LASTPIN (-2550 2825) $PN 2
R 1
J 2
(-2560 2815);
DISPLAY 0.808511 (-2560 2815);
PAINT ORANGE (-2560 2815);
FORCEPROP 2 LASTPIN (-2550 3075) $PN 1
R 1
J 0
(-2560 3085);
DISPLAY 0.808511 (-2560 3085);
PAINT ORANGE (-2560 3085);
FORCEPROP 2 LAST ATTRIBUTE 1 OHM
J 0
(-2525 3000);
DISPLAY 0.638298 (-2525 3000);
PAINT GREEN (-2525 3000);
FORCEPROP 1 LAST VALUE 1R3F-GP
J 0
(-2525 3050);
DISPLAY 0.617021 (-2525 3050);
PAINT GREEN (-2525 3050);
FORCEPROP 2 LAST RATED 1/10W
J 0
(-2525 2900);
DISPLAY 0.638298 (-2525 2900);
PAINT GREEN (-2525 2900);
FORCEPROP 2 LAST PACK_SIZE 0603
J 0
(-2525 2850);
DISPLAY 0.638298 (-2525 2850);
PAINT GREEN (-2525 2850);
FORCEPROP 1 LAST PATH I114
J 0
(-2550 2950);
DISPLAY 0.617021 (-2550 2950);
PAINT GREEN (-2550 2950);
DISPLAY INVISIBLE (-2550 2950);
FORCEPROP 1 LAST PACK_TYPE RCL_GP
J 0
(-2550 2950);
DISPLAY 0.617021 (-2550 2950);
PAINT GREEN (-2550 2950);
DISPLAY INVISIBLE (-2550 2950);
FORCEPROP 2 LAST SEC 1
J 0
(-2500 3050);
DISPLAY 0.680851 (-2500 3050);
PAINT MONO (-2500 3050);
DISPLAY INVISIBLE (-2500 3050);
FORCEPROP 2 LAST SEC_TYPE RCL_GP
J 0
(-2500 3050);
DISPLAY 1.021277 (-2500 3050);
PAINT ORANGE (-2500 3050);
DISPLAY INVISIBLE (-2500 3050);
FORCEPROP 1 LAST PART_NUMBER 64.1R005.55L
J 0
(-2550 2950);
DISPLAY 0.617021 (-2550 2950);
PAINT GREEN (-2550 2950);
DISPLAY INVISIBLE (-2550 2950);
FORCEPROP 2 LAST CDS_LIB w_hdl
J 0
(-2550 2950);
DISPLAY INVISIBLE (-2550 2950);
FORCEPROP 1 LAST CDS_LMAN_SYM_OUTLINE -50,75,50,-75
J 0
(-2550 2950);
DISPLAY 0.468085 (-2550 2950);
PAINT GREEN (-2550 2950);
DISPLAY INVISIBLE (-2550 2950);
FORCEADD 1R3F-GP..1
(-2550 525);
FORCEPROP 2 LASTPIN (-2550 650) $PN 1
R 1
J 0
(-2560 660);
DISPLAY 0.808511 (-2560 660);
PAINT ORANGE (-2560 660);
FORCEPROP 0 LAST POP NOPOP
J 0
(-2500 400);
DISPLAY 0.638298 (-2500 400);
PAINT RED (-2500 400);
FORCEPROP 2 LAST TOLERANCE 1%
J 0
(-2500 450);
DISPLAY 0.638298 (-2500 450);
PAINT GREEN (-2500 450);
FORCEPROP 1 LAST LOCATION RT4
J 0
(-2500 600);
DISPLAY 0.617021 (-2500 600);
PAINT GREEN (-2500 600);
FORCEPROP 2 LASTPIN (-2550 400) $PN 2
R 1
J 2
(-2560 390);
DISPLAY 0.808511 (-2560 390);
PAINT ORANGE (-2560 390);
FORCEPROP 1 LAST VALUE 1R3F-GP
J 0
(-2500 550);
DISPLAY 0.617021 (-2500 550);
PAINT GREEN (-2500 550);
FORCEPROP 2 LAST ATTRIBUTE 1 OHM
J 0
(-2500 500);
DISPLAY 0.638298 (-2500 500);
PAINT GREEN (-2500 500);
FORCEPROP 2 LAST RATED 1/10W
J 0
(-2350 500);
DISPLAY 0.638298 (-2350 500);
PAINT GREEN (-2350 500);
FORCEPROP 2 LAST PACK_SIZE 0603
J 0
(-2350 450);
DISPLAY 0.638298 (-2350 450);
PAINT GREEN (-2350 450);
FORCEPROP 1 LAST PATH I115
J 0
(-2550 525);
DISPLAY 0.617021 (-2550 525);
PAINT GREEN (-2550 525);
DISPLAY INVISIBLE (-2550 525);
FORCEPROP 1 LAST CDS_LMAN_SYM_OUTLINE -50,75,50,-75
J 0
(-2550 525);
DISPLAY 0.468085 (-2550 525);
PAINT GREEN (-2550 525);
DISPLAY INVISIBLE (-2550 525);
FORCEPROP 2 LAST CDS_LIB w_hdl
J 0
(-2550 525);
DISPLAY INVISIBLE (-2550 525);
FORCEPROP 1 LAST PART_NUMBER 64.1R005.55L
J 0
(-2550 525);
DISPLAY 0.617021 (-2550 525);
PAINT GREEN (-2550 525);
DISPLAY INVISIBLE (-2550 525);
FORCEPROP 2 LAST SEC_TYPE RCL_GP
J 0
(-2500 625);
DISPLAY 1.021277 (-2500 625);
PAINT ORANGE (-2500 625);
DISPLAY INVISIBLE (-2500 625);
FORCEPROP 2 LAST SEC 1
J 0
(-2500 625);
DISPLAY 0.680851 (-2500 625);
PAINT MONO (-2500 625);
DISPLAY INVISIBLE (-2500 625);
FORCEPROP 1 LAST PACK_TYPE RCL_GP
J 0
(-2550 525);
DISPLAY 0.617021 (-2550 525);
PAINT GREEN (-2550 525);
DISPLAY INVISIBLE (-2550 525);
FORCEADD OFFPAGE..2
(-1675 1375);
FORCEPROP 2 LAST $XR3 201 
J 0
(-1126 1375);
DISPLAY 0.638298 (-1126 1375);
PAINT MONO (-1126 1375);
FORCEPROP 2 LAST $XR2 204 
J 0
(-1246 1375);
DISPLAY 0.638298 (-1246 1375);
PAINT MONO (-1246 1375);
FORCEPROP 2 LAST $XR1 203 
J 0
(-1366 1375);
DISPLAY 0.638298 (-1366 1375);
PAINT MONO (-1366 1375);
FORCEPROP 2 LAST $XR0 202 
J 0
(-1486 1375);
DISPLAY 0.638298 (-1486 1375);
PAINT MONO (-1486 1375);
FORCEPROP 2 LAST ROOM PVCCIN_CPU0_PWR_VR
J 0
(-2075 1450);
DISPLAY 1.936170 (-2075 1450);
PAINT ORANGE (-2075 1450);
DISPLAY INVISIBLE (-2075 1450);
FORCEPROP 2 LAST CDS_LIB mstr_standard
J 0
(-1675 1375);
PAINT ORANGE (-1675 1375);
DISPLAY INVISIBLE (-1675 1375);
FORCEPROP 2 LAST PATH I12
J 0
(-1495 1450);
DISPLAY 1.021277 (-1495 1450);
PAINT ORANGE (-1495 1450);
DISPLAY INVISIBLE (-1495 1450);
FORCEPROP 2 LAST BOM_COST PROC_VRD_VCCIN_CPU0
J 0
(-1475 1425);
DISPLAY 1.446809 (-1475 1425);
PAINT MONO (-1475 1425);
DISPLAY INVISIBLE (-1475 1425);
FORCEPROP 1 LAST OFFPAGE TRUE
J 0
(-1350 1250);
DISPLAY 1.723404 (-1350 1250);
PAINT GREEN (-1350 1250);
DISPLAY INVISIBLE (-1350 1250);
FORCEPROP 1 LAST COMMENT_BODY TRUE
J 0
(-1720 1280);
DISPLAY 1.723404 (-1720 1280);
PAINT GREEN (-1720 1280);
DISPLAY INVISIBLE (-1720 1280);
FORCEADD GND..1
(-2800 3125);
FORCEPROP 3 LASTPIN (-2800 3175) SIG_NAME GND\g
J 0
(-2790 3185);
DISPLAY 0.659574 (-2790 3185);
PAINT MONO (-2790 3185);
DISPLAY INVISIBLE (-2790 3185);
FORCEPROP 2 LAST CDS_LIB mstr_symbols
J 0
(-2800 3125);
DISPLAY 1.936170 (-2800 3125);
PAINT ORANGE (-2800 3125);
DISPLAY INVISIBLE (-2800 3125);
FORCEPROP 1 LAST PATH I13
J 0
(-2725 3125);
DISPLAY 0.872340 (-2725 3125);
PAINT AQUA (-2725 3125);
DISPLAY INVISIBLE (-2725 3125);
FORCEPROP 2 LAST ROOM PVCCIN_CPU0_PWR_VR
J 0
(-3350 3200);
DISPLAY 1.936170 (-3350 3200);
PAINT ORANGE (-3350 3200);
DISPLAY INVISIBLE (-3350 3200);
FORCEPROP 2 LAST BOM_COST PROC_VRD_VCCIN_CPU0
J 0
(-3175 3200);
DISPLAY 1.446809 (-3175 3200);
PAINT MONO (-3175 3200);
DISPLAY INVISIBLE (-3175 3200);
FORCEPROP 1 LAST VOLTAGE 0
J 0
(-2800 3125);
PAINT SKYBLUE (-2800 3125);
DISPLAY INVISIBLE (-2800 3125);
FORCEPROP 1 LAST SIZE 1B
J 0
(-2725 3075);
DISPLAY 1.723404 (-2725 3075);
PAINT GREEN (-2725 3075);
DISPLAY INVISIBLE (-2725 3075);
FORCEPROP 1 LAST BODY_TYPE PLUMBING
J 0
(-2845 3082);
DISPLAY 0.340426 (-2845 3082);
PAINT GREEN (-2845 3082);
DISPLAY INVISIBLE (-2845 3082);
FORCEPROP 1 LAST HDL_POWER GND
J 0
(-2800 3275);
DISPLAY 1.723404 (-2800 3275);
PAINT GREEN (-2800 3275);
DISPLAY INVISIBLE (-2800 3275);
FORCEADD CAP..1
(-4900 4125);
FORCEPROP 1 LAST LOCATION C4E5
J 0
(-4850 4225);
DISPLAY 0.617021 (-4850 4225);
PAINT AQUA (-4850 4225);
FORCEPROP 1 LASTPIN (-4900 4225) $PN 1
J 0
(-4890 4205);
DISPLAY 0.617021 (-4890 4205);
PAINT ORANGE (-4890 4205);
FORCEPROP 1 LAST VALUE 0.22UF
J 0
(-4850 4175);
DISPLAY 0.617021 (-4850 4175);
PAINT SKYBLUE (-4850 4175);
FORCEPROP 1 LASTPIN (-4900 4025) $PN 2
J 0
(-4890 4005);
DISPLAY 0.617021 (-4890 4005);
PAINT ORANGE (-4890 4005);
FORCEPROP 1 LAST VOLTAGE 16V
J 0
(-4850 4125);
DISPLAY 0.617021 (-4850 4125);
PAINT SKYBLUE (-4850 4125);
FORCEPROP 1 LAST TOLERANCE 10%
J 0
(-4850 4075);
DISPLAY 0.617021 (-4850 4075);
PAINT SKYBLUE (-4850 4075);
FORCEPROP 1 LAST MATERIAL X7R
J 0
(-4850 4025);
DISPLAY 0.617021 (-4850 4025);
PAINT SKYBLUE (-4850 4025);
FORCEPROP 1 LAST PART_NUMBER A36096-155
J 0
(-4850 3975);
DISPLAY 0.617021 (-4850 3975);
PAINT BLUE (-4850 3975);
FORCEPROP 1 LAST PACK_TYPE 0402
J 0
(-4850 3925);
DISPLAY 0.617021 (-4850 3925);
PAINT SKYBLUE (-4850 3925);
FORCEPROP 2 LAST ROOM PVCCIN_CPU0_PWR_VR
J 0
(-4850 4275);
DISPLAY 1.361702 (-4850 4275);
PAINT ORANGE (-4850 4275);
DISPLAY INVISIBLE (-4850 4275);
FORCEPROP 1 LAST PATH I18
J 0
(-4850 4275);
DISPLAY 0.978723 (-4850 4275);
PAINT WHITE (-4850 4275);
DISPLAY INVISIBLE (-4850 4275);
FORCEPROP 2 LAST CDS_LOCATION C4E5
J 0
(-4850 4225);
DISPLAY 0.617021 (-4850 4225);
PAINT AQUA (-4850 4225);
DISPLAY INVISIBLE (-4850 4225);
FORCEPROP 2 LAST SEC 1
J 0
(-4850 4325);
DISPLAY 0.680851 (-4850 4325);
PAINT MONO (-4850 4325);
DISPLAY INVISIBLE (-4850 4325);
FORCEPROP 2 LAST SEC_TYPE 0402
J 0
(-4850 4325);
DISPLAY 1.021277 (-4850 4325);
PAINT ORANGE (-4850 4325);
DISPLAY INVISIBLE (-4850 4325);
FORCEPROP 2 LAST CDS_LIB mstr_discrete
J 0
(-4900 4125);
PAINT ORANGE (-4900 4125);
DISPLAY INVISIBLE (-4900 4125);
FORCEADD OFFPAGE..2
(-1550 4350);
FORCEPROP 2 LAST $XR0 201 
J 0
(-1361 4350);
DISPLAY 0.638298 (-1361 4350);
PAINT MONO (-1361 4350);
FORCEPROP 2 LAST CDS_LIB mstr_standard
J 0
(-1550 4350);
DISPLAY 1.936170 (-1550 4350);
PAINT ORANGE (-1550 4350);
DISPLAY INVISIBLE (-1550 4350);
FORCEPROP 2 LAST ROOM PVCCIN_CPU0_PWR_VR
J 0
(-1950 4425);
DISPLAY 1.936170 (-1950 4425);
PAINT ORANGE (-1950 4425);
DISPLAY INVISIBLE (-1950 4425);
FORCEPROP 2 LAST PATH I2
J 0
(-1345 4400);
DISPLAY 1.021277 (-1345 4400);
PAINT ORANGE (-1345 4400);
DISPLAY INVISIBLE (-1345 4400);
FORCEPROP 2 LAST BOM_COST PROC_VRD_VCCIN_CPU0
J 0
(-1350 4400);
DISPLAY 1.446809 (-1350 4400);
PAINT MONO (-1350 4400);
DISPLAY INVISIBLE (-1350 4400);
FORCEPROP 1 LAST OFFPAGE TRUE
J 0
(-1225 4225);
DISPLAY 1.723404 (-1225 4225);
PAINT GREEN (-1225 4225);
DISPLAY INVISIBLE (-1225 4225);
FORCEPROP 1 LAST COMMENT_BODY TRUE
J 0
(-1595 4255);
DISPLAY 1.723404 (-1595 4255);
PAINT GREEN (-1595 4255);
DISPLAY INVISIBLE (-1595 4255);
FORCEADD CAP..1
R 2
(-5850 3450);
FORCEPROP 1 LAST VALUE 0.220UF
J 2
(-5900 3500);
DISPLAY 0.617021 (-5900 3500);
PAINT SKYBLUE (-5900 3500);
FORCEPROP 1 LASTPIN (-5850 3350) $PN 2
J 2
(-5860 3330);
DISPLAY 0.617021 (-5860 3330);
PAINT ORANGE (-5860 3330);
FORCEPROP 1 LAST TOLERANCE 10%
J 2
(-5900 3400);
DISPLAY 0.617021 (-5900 3400);
PAINT SKYBLUE (-5900 3400);
FORCEPROP 1 LAST VOLTAGE 16V
J 2
(-5900 3450);
DISPLAY 0.617021 (-5900 3450);
PAINT SKYBLUE (-5900 3450);
FORCEPROP 1 LASTPIN (-5850 3550) $PN 1
J 2
(-5860 3530);
DISPLAY 0.617021 (-5860 3530);
PAINT ORANGE (-5860 3530);
FORCEPROP 1 LAST LOCATION C4E17
J 2
(-5900 3550);
DISPLAY 0.617021 (-5900 3550);
PAINT AQUA (-5900 3550);
FORCEPROP 1 LAST MATERIAL X7R
J 2
(-5900 3350);
DISPLAY 0.617021 (-5900 3350);
PAINT SKYBLUE (-5900 3350);
FORCEPROP 1 LAST PACK_TYPE 0402
J 2
(-5900 3250);
DISPLAY 0.617021 (-5900 3250);
PAINT SKYBLUE (-5900 3250);
FORCEPROP 1 LAST PART_NUMBER A36096-104
J 2
(-5900 3300);
DISPLAY 0.617021 (-5900 3300);
PAINT BLUE (-5900 3300);
FORCEPROP 2 LAST CDS_LOCATION C4E17
J 2
(-5900 3550);
DISPLAY 0.617021 (-5900 3550);
PAINT AQUA (-5900 3550);
DISPLAY INVISIBLE (-5900 3550);
FORCEPROP 2 LAST CDS_LIB mstr_discrete
J 0
(-5850 3450);
PAINT ORANGE (-5850 3450);
DISPLAY INVISIBLE (-5850 3450);
FORCEPROP 2 LAST SEC_TYPE 0402
J 0
(-5900 3650);
DISPLAY 1.021277 (-5900 3650);
PAINT ORANGE (-5900 3650);
DISPLAY INVISIBLE (-5900 3650);
FORCEPROP 0 LAST SPOF TRUE
J 0
(-5900 3650);
DISPLAY 1.021277 (-5900 3650);
PAINT ORANGE (-5900 3650);
DISPLAY INVISIBLE (-5900 3650);
FORCEPROP 2 LAST SEC 1
J 0
(-5900 3650);
DISPLAY 0.680851 (-5900 3650);
PAINT MONO (-5900 3650);
DISPLAY INVISIBLE (-5900 3650);
FORCEPROP 2 LAST NO_XNET_CONNECTION 1
J 0
(-5900 3650);
PAINT MONO (-5900 3650);
DISPLAY INVISIBLE (-5900 3650);
FORCEPROP 1 LAST PATH I22
J 2
(-5900 3600);
DISPLAY 0.978723 (-5900 3600);
PAINT WHITE (-5900 3600);
DISPLAY INVISIBLE (-5900 3600);
FORCEPROP 2 LAST ROOM PVCCIN_CPU0_PWR_VR
J 0
(-5925 3600);
DISPLAY 1.361702 (-5925 3600);
PAINT ORANGE (-5925 3600);
DISPLAY INVISIBLE (-5925 3600);
FORCEADD CAP..1
(-4950 1425);
FORCEPROP 1 LAST LOCATION C4E27
J 0
(-4900 1525);
DISPLAY 0.617021 (-4900 1525);
PAINT AQUA (-4900 1525);
FORCEPROP 1 LAST VALUE 0.22UF
J 0
(-4900 1475);
DISPLAY 0.617021 (-4900 1475);
PAINT SKYBLUE (-4900 1475);
FORCEPROP 1 LAST VOLTAGE 16V
J 0
(-4900 1425);
DISPLAY 0.617021 (-4900 1425);
PAINT SKYBLUE (-4900 1425);
FORCEPROP 1 LAST PART_NUMBER A36096-155
J 0
(-4900 1275);
DISPLAY 0.617021 (-4900 1275);
PAINT BLUE (-4900 1275);
FORCEPROP 1 LAST MATERIAL X7R
J 0
(-4900 1325);
DISPLAY 0.617021 (-4900 1325);
PAINT SKYBLUE (-4900 1325);
FORCEPROP 1 LAST TOLERANCE 10%
J 0
(-4900 1375);
DISPLAY 0.617021 (-4900 1375);
PAINT SKYBLUE (-4900 1375);
FORCEPROP 1 LASTPIN (-4950 1525) $PN 1
J 0
(-4940 1505);
DISPLAY 0.617021 (-4940 1505);
PAINT ORANGE (-4940 1505);
FORCEPROP 1 LASTPIN (-4950 1325) $PN 2
J 0
(-4940 1305);
DISPLAY 0.617021 (-4940 1305);
PAINT ORANGE (-4940 1305);
FORCEPROP 1 LAST PACK_TYPE 0402
J 0
(-4900 1225);
DISPLAY 0.617021 (-4900 1225);
PAINT SKYBLUE (-4900 1225);
FORCEPROP 2 LAST ROOM PVCCIN_CPU0_PWR_VR
J 0
(-4900 1575);
DISPLAY 1.361702 (-4900 1575);
PAINT ORANGE (-4900 1575);
DISPLAY INVISIBLE (-4900 1575);
FORCEPROP 1 LAST PATH I24
J 0
(-4900 1575);
DISPLAY 0.978723 (-4900 1575);
PAINT WHITE (-4900 1575);
DISPLAY INVISIBLE (-4900 1575);
FORCEPROP 2 LAST SEC 1
J 0
(-4900 1625);
DISPLAY 0.680851 (-4900 1625);
PAINT MONO (-4900 1625);
DISPLAY INVISIBLE (-4900 1625);
FORCEPROP 2 LAST SEC_TYPE 0402
J 0
(-4900 1625);
DISPLAY 1.021277 (-4900 1625);
PAINT ORANGE (-4900 1625);
DISPLAY INVISIBLE (-4900 1625);
FORCEPROP 2 LAST CDS_LIB mstr_discrete
J 0
(-4950 1425);
PAINT ORANGE (-4950 1425);
DISPLAY INVISIBLE (-4950 1425);
FORCEADD PVCCIN_CPU0..1
(-500 1050);
FORCEPROP 3 LASTPIN (-500 1000) SIG_NAME PVCCIN_CPU0\g
J 0
(-490 1010);
DISPLAY 0.659574 (-490 1010);
PAINT MONO (-490 1010);
DISPLAY INVISIBLE (-490 1010);
FORCEPROP 1 LAST VOLTAGE 2.0V
J 0
(-545 1007);
DISPLAY 0.340426 (-545 1007);
PAINT SKYBLUE (-545 1007);
DISPLAY INVISIBLE (-545 1007);
FORCEPROP 2 LAST CDS_LIB mstr_symbols
J 0
(-500 1050);
PAINT ORANGE (-500 1050);
DISPLAY INVISIBLE (-500 1050);
FORCEPROP 1 LAST PATH I26
J 0
(-450 1075);
DISPLAY 0.872340 (-450 1075);
PAINT AQUA (-450 1075);
DISPLAY INVISIBLE (-450 1075);
FORCEPROP 1 LAST BODY_TYPE PLUMBING
J 0
(-545 1007);
DISPLAY 0.340426 (-545 1007);
PAINT GREEN (-545 1007);
DISPLAY INVISIBLE (-545 1007);
FORCEPROP 1 LAST HDL_POWER PVCCIN_CPU0
J 1
(-500 1100);
DISPLAY 0.872340 (-500 1100);
PAINT GREEN (-500 1100);
DISPLAY INVISIBLE (-500 1100);
FORCEADD CAP_A..1
(-850 750);
FORCEPROP 0 LAST GROUP PWR_MLCC_CAP
J 0
(-802 552);
DISPLAY 0.638298 (-802 552);
PAINT BROWN (-802 552);
DISPLAY BOTH (-802 552);
FORCEPROP 1 LAST TOLERANCE 20%
J 0
(-800 750);
DISPLAY 0.617021 (-800 750);
PAINT SKYBLUE (-800 750);
FORCEPROP 1 LAST VOLTAGE 4V
J 0
(-800 800);
DISPLAY 0.617021 (-800 800);
PAINT SKYBLUE (-800 800);
FORCEPROP 1 LAST LOCATION C4E11
J 0
(-800 900);
DISPLAY 0.617021 (-800 900);
PAINT AQUA (-800 900);
FORCEPROP 1 LAST VALUE 22.0UF
J 0
(-800 850);
DISPLAY 0.617021 (-800 850);
PAINT SKYBLUE (-800 850);
FORCEPROP 1 LAST MATERIAL X6S
J 0
(-800 700);
DISPLAY 0.617021 (-800 700);
PAINT SKYBLUE (-800 700);
FORCEPROP 1 LAST PART_NUMBER E15431-004
J 0
(-800 650);
DISPLAY 0.617021 (-800 650);
PAINT BLUE (-800 650);
FORCEPROP 1 LAST PACK_TYPE 0603V
J 0
(-800 600);
DISPLAY 0.617021 (-800 600);
PAINT SKYBLUE (-800 600);
FORCEPROP 1 LASTPIN (-850 650) $PN 2
J 0
(-840 630);
DISPLAY 0.617021 (-840 630);
PAINT ORANGE (-840 630);
FORCEPROP 1 LASTPIN (-850 850) $PN 1
J 0
(-840 830);
DISPLAY 0.617021 (-840 830);
PAINT ORANGE (-840 830);
FORCEPROP 2 LAST SEC 1
J 0
(-795 950);
DISPLAY 0.680851 (-795 950);
PAINT MONO (-795 950);
DISPLAY INVISIBLE (-795 950);
FORCEPROP 2 LAST SEC_TYPE 0603V
J 0
(-795 950);
DISPLAY 1.021277 (-795 950);
PAINT ORANGE (-795 950);
DISPLAY INVISIBLE (-795 950);
FORCEPROP 2 LAST CDS_LOCATION C4E11
J 0
(-800 850);
DISPLAY 0.617021 (-800 850);
PAINT AQUA (-800 850);
DISPLAY INVISIBLE (-800 850);
FORCEPROP 2 LAST BOM_COST PROC_VRD_VCCIN_CPU0
J 0
(-800 900);
DISPLAY 1.446809 (-800 900);
PAINT MONO (-800 900);
DISPLAY INVISIBLE (-800 900);
FORCEPROP 2 LAST CDS_SEC 1
J 0
(-800 900);
PAINT ORANGE (-800 900);
DISPLAY INVISIBLE (-800 900);
FORCEPROP 1 LAST PATH I27
J 0
(-800 900);
DISPLAY 0.978723 (-800 900);
PAINT WHITE (-800 900);
DISPLAY INVISIBLE (-800 900);
FORCEPROP 2 LAST ROOM PVCCIN_CPU0_PWR_VR
J 0
(-800 900);
DISPLAY 1.446809 (-800 900);
PAINT MONO (-800 900);
DISPLAY INVISIBLE (-800 900);
FORCEPROP 2 LAST CDS_LIB dev_discrete
J 0
(-850 750);
PAINT ORANGE (-850 750);
DISPLAY INVISIBLE (-850 750);
FORCEADD GND..1
(-500 475);
FORCEPROP 3 LASTPIN (-500 525) SIG_NAME GND\g
J 0
(-490 535);
DISPLAY 0.659574 (-490 535);
PAINT MONO (-490 535);
DISPLAY INVISIBLE (-490 535);
FORCEPROP 1 LAST HDL_POWER GND
J 0
(-500 625);
DISPLAY 1.723404 (-500 625);
PAINT GREEN (-500 625);
DISPLAY INVISIBLE (-500 625);
FORCEPROP 1 LAST BODY_TYPE PLUMBING
J 0
(-545 432);
DISPLAY 0.340426 (-545 432);
PAINT GREEN (-545 432);
DISPLAY INVISIBLE (-545 432);
FORCEPROP 2 LAST ROOM PVCCIN_CPU0_PWR_VR
J 0
(-1050 550);
DISPLAY 1.936170 (-1050 550);
PAINT ORANGE (-1050 550);
DISPLAY INVISIBLE (-1050 550);
FORCEPROP 2 LAST BOM_COST PROC_VRD_VCCIN_CPU0
J 0
(-875 550);
DISPLAY 1.446809 (-875 550);
PAINT MONO (-875 550);
DISPLAY INVISIBLE (-875 550);
FORCEPROP 1 LAST SIZE 1B
J 0
(-425 425);
DISPLAY 1.723404 (-425 425);
PAINT GREEN (-425 425);
DISPLAY INVISIBLE (-425 425);
FORCEPROP 1 LAST PATH I28
J 0
(-425 475);
DISPLAY 0.872340 (-425 475);
PAINT AQUA (-425 475);
DISPLAY INVISIBLE (-425 475);
FORCEPROP 2 LAST CDS_LIB mstr_symbols
J 0
(-500 475);
PAINT ORANGE (-500 475);
DISPLAY INVISIBLE (-500 475);
FORCEPROP 1 LAST VOLTAGE 0
J 0
(-500 475);
PAINT SKYBLUE (-500 475);
DISPLAY INVISIBLE (-500 475);
FORCEADD OFFPAGE..2
(-1700 4000);
FORCEPROP 2 LAST $XR3 201 
J 0
(-1151 4000);
DISPLAY 0.638298 (-1151 4000);
PAINT MONO (-1151 4000);
FORCEPROP 2 LAST $XR2 204 
J 0
(-1271 4000);
DISPLAY 0.638298 (-1271 4000);
PAINT MONO (-1271 4000);
FORCEPROP 2 LAST $XR1 203 
J 0
(-1391 4000);
DISPLAY 0.638298 (-1391 4000);
PAINT MONO (-1391 4000);
FORCEPROP 2 LAST $XR0 202 
J 0
(-1511 4000);
DISPLAY 0.638298 (-1511 4000);
PAINT MONO (-1511 4000);
FORCEPROP 2 LAST ROOM PVCCIN_CPU0_PWR_VR
J 0
(-2100 4075);
DISPLAY 1.936170 (-2100 4075);
PAINT ORANGE (-2100 4075);
DISPLAY INVISIBLE (-2100 4075);
FORCEPROP 2 LAST PATH I3
J 0
(-1520 4075);
DISPLAY 1.021277 (-1520 4075);
PAINT ORANGE (-1520 4075);
DISPLAY INVISIBLE (-1520 4075);
FORCEPROP 2 LAST CDS_LIB mstr_standard
J 0
(-1700 4000);
PAINT ORANGE (-1700 4000);
DISPLAY INVISIBLE (-1700 4000);
FORCEPROP 2 LAST BOM_COST PROC_VRD_VCCIN_CPU0
J 0
(-1500 4050);
DISPLAY 1.446809 (-1500 4050);
PAINT MONO (-1500 4050);
DISPLAY INVISIBLE (-1500 4050);
FORCEPROP 1 LAST OFFPAGE TRUE
J 0
(-1375 3875);
DISPLAY 1.723404 (-1375 3875);
PAINT GREEN (-1375 3875);
DISPLAY INVISIBLE (-1375 3875);
FORCEPROP 1 LAST COMMENT_BODY TRUE
J 0
(-1745 3905);
DISPLAY 1.723404 (-1745 3905);
PAINT GREEN (-1745 3905);
DISPLAY INVISIBLE (-1745 3905);
FORCEADD GND..1
(-2800 525);
FORCEPROP 3 LASTPIN (-2800 575) SIG_NAME GND\g
J 0
(-2790 585);
DISPLAY 0.659574 (-2790 585);
PAINT MONO (-2790 585);
DISPLAY INVISIBLE (-2790 585);
FORCEPROP 2 LAST ROOM PVCCIN_CPU0_PWR_VR
J 0
(-3350 600);
DISPLAY 1.936170 (-3350 600);
PAINT ORANGE (-3350 600);
DISPLAY INVISIBLE (-3350 600);
FORCEPROP 2 LAST BOM_COST PROC_VRD_VCCIN_CPU0
J 0
(-3175 600);
DISPLAY 1.446809 (-3175 600);
PAINT MONO (-3175 600);
DISPLAY INVISIBLE (-3175 600);
FORCEPROP 1 LAST SIZE 1B
J 0
(-2725 475);
DISPLAY 1.723404 (-2725 475);
PAINT GREEN (-2725 475);
DISPLAY INVISIBLE (-2725 475);
FORCEPROP 1 LAST VOLTAGE 0
J 0
(-2800 525);
PAINT SKYBLUE (-2800 525);
DISPLAY INVISIBLE (-2800 525);
FORCEPROP 2 LAST CDS_LIB mstr_symbols
J 0
(-2800 525);
PAINT ORANGE (-2800 525);
DISPLAY INVISIBLE (-2800 525);
FORCEPROP 1 LAST PATH I30
J 0
(-2725 525);
DISPLAY 0.872340 (-2725 525);
PAINT AQUA (-2725 525);
DISPLAY INVISIBLE (-2725 525);
FORCEPROP 1 LAST BODY_TYPE PLUMBING
J 0
(-2845 482);
DISPLAY 0.340426 (-2845 482);
PAINT GREEN (-2845 482);
DISPLAY INVISIBLE (-2845 482);
FORCEPROP 1 LAST HDL_POWER GND
J 0
(-2800 675);
DISPLAY 1.723404 (-2800 675);
PAINT GREEN (-2800 675);
DISPLAY INVISIBLE (-2800 675);
FORCEADD CAP..1
R 2
(-5950 825);
FORCEPROP 1 LAST PART_NUMBER A36096-104
J 2
(-6000 675);
DISPLAY 0.617021 (-6000 675);
PAINT BLUE (-6000 675);
FORCEPROP 1 LASTPIN (-5950 925) $PN 1
J 2
(-5960 905);
DISPLAY 0.617021 (-5960 905);
PAINT ORANGE (-5960 905);
FORCEPROP 1 LAST PACK_TYPE 0402
J 2
(-6000 625);
DISPLAY 0.617021 (-6000 625);
PAINT SKYBLUE (-6000 625);
FORCEPROP 1 LAST LOCATION C4D50
J 2
(-6000 925);
DISPLAY 0.617021 (-6000 925);
PAINT AQUA (-6000 925);
FORCEPROP 1 LAST VALUE 0.220UF
J 2
(-6000 875);
DISPLAY 0.617021 (-6000 875);
PAINT SKYBLUE (-6000 875);
FORCEPROP 1 LAST VOLTAGE 16V
J 2
(-6000 825);
DISPLAY 0.617021 (-6000 825);
PAINT SKYBLUE (-6000 825);
FORCEPROP 1 LAST TOLERANCE 10%
J 2
(-6000 775);
DISPLAY 0.617021 (-6000 775);
PAINT SKYBLUE (-6000 775);
FORCEPROP 1 LAST MATERIAL X7R
J 2
(-6000 725);
DISPLAY 0.617021 (-6000 725);
PAINT SKYBLUE (-6000 725);
FORCEPROP 1 LASTPIN (-5950 725) $PN 2
J 2
(-5960 705);
DISPLAY 0.617021 (-5960 705);
PAINT ORANGE (-5960 705);
FORCEPROP 2 LAST NO_XNET_CONNECTION 1
J 0
(-6000 1025);
PAINT MONO (-6000 1025);
DISPLAY INVISIBLE (-6000 1025);
FORCEPROP 2 LAST SEC 1
J 0
(-6000 1025);
DISPLAY 0.680851 (-6000 1025);
PAINT MONO (-6000 1025);
DISPLAY INVISIBLE (-6000 1025);
FORCEPROP 0 LAST SPOF TRUE
J 0
(-6000 1025);
DISPLAY 1.021277 (-6000 1025);
PAINT ORANGE (-6000 1025);
DISPLAY INVISIBLE (-6000 1025);
FORCEPROP 2 LAST SEC_TYPE 0402
J 0
(-6000 1025);
DISPLAY 1.021277 (-6000 1025);
PAINT ORANGE (-6000 1025);
DISPLAY INVISIBLE (-6000 1025);
FORCEPROP 2 LAST ROOM PVCCIN_CPU0_PWR_VR
J 0
(-6000 975);
DISPLAY 1.361702 (-6000 975);
PAINT ORANGE (-6000 975);
DISPLAY INVISIBLE (-6000 975);
FORCEPROP 2 LAST CDS_LIB mstr_discrete
J 0
(-5950 825);
PAINT ORANGE (-5950 825);
DISPLAY INVISIBLE (-5950 825);
FORCEPROP 1 LAST PATH I32
J 2
(-6000 975);
DISPLAY 0.978723 (-6000 975);
PAINT WHITE (-6000 975);
DISPLAY INVISIBLE (-6000 975);
FORCEADD CAP..1
(-5700 4025);
FORCEPROP 1 LAST MATERIAL X6S
J 0
(-5650 3925);
DISPLAY 0.617021 (-5650 3925);
PAINT SKYBLUE (-5650 3925);
FORCEPROP 1 LAST LOCATION C4E10
J 0
(-5650 4125);
DISPLAY 0.617021 (-5650 4125);
PAINT AQUA (-5650 4125);
FORCEPROP 1 LASTPIN (-5700 4125) $PN 1
J 0
(-5690 4105);
DISPLAY 0.617021 (-5690 4105);
PAINT ORANGE (-5690 4105);
FORCEPROP 1 LAST VALUE 1.0UF
J 0
(-5650 4075);
DISPLAY 0.617021 (-5650 4075);
PAINT SKYBLUE (-5650 4075);
FORCEPROP 1 LAST VOLTAGE 16V
J 0
(-5650 4025);
DISPLAY 0.617021 (-5650 4025);
PAINT SKYBLUE (-5650 4025);
FORCEPROP 1 LAST TOLERANCE 10%
J 0
(-5650 3975);
DISPLAY 0.617021 (-5650 3975);
PAINT SKYBLUE (-5650 3975);
FORCEPROP 1 LAST PACK_TYPE 0402
J 0
(-5650 3825);
DISPLAY 0.617021 (-5650 3825);
PAINT SKYBLUE (-5650 3825);
FORCEPROP 1 LAST PART_NUMBER D97712-011
J 0
(-5650 3875);
DISPLAY 0.617021 (-5650 3875);
PAINT BLUE (-5650 3875);
FORCEPROP 1 LASTPIN (-5700 3925) $PN 2
J 0
(-5690 3905);
DISPLAY 0.617021 (-5690 3905);
PAINT ORANGE (-5690 3905);
FORCEPROP 2 LAST ROOM PVCCIN_CPU0_PWR_VR
J 0
(-5650 4175);
DISPLAY 1.361702 (-5650 4175);
PAINT ORANGE (-5650 4175);
DISPLAY INVISIBLE (-5650 4175);
FORCEPROP 1 LAST PATH I34
J 0
(-5650 4175);
DISPLAY 0.978723 (-5650 4175);
PAINT WHITE (-5650 4175);
DISPLAY INVISIBLE (-5650 4175);
FORCEPROP 2 LAST CDS_LOCATION C4E10
J 0
(-5650 4125);
DISPLAY 0.617021 (-5650 4125);
PAINT AQUA (-5650 4125);
DISPLAY INVISIBLE (-5650 4125);
FORCEPROP 2 LAST SEC 1
J 0
(-5650 4225);
DISPLAY 0.680851 (-5650 4225);
PAINT MONO (-5650 4225);
DISPLAY INVISIBLE (-5650 4225);
FORCEPROP 2 LAST SEC_TYPE 0402
J 0
(-5650 4225);
DISPLAY 1.021277 (-5650 4225);
PAINT ORANGE (-5650 4225);
DISPLAY INVISIBLE (-5650 4225);
FORCEPROP 2 LAST CDS_LIB mstr_discrete
J 0
(-5700 4025);
PAINT ORANGE (-5700 4025);
DISPLAY INVISIBLE (-5700 4025);
FORCEADD CAP_A..1
(-5975 4050);
FORCEPROP 1 LASTPIN (-5975 4150) $PN 1
J 0
(-5965 4130);
DISPLAY 0.617021 (-5965 4130);
PAINT ORANGE (-5965 4130);
FORCEPROP 1 LASTPIN (-5975 3950) $PN 2
J 0
(-5965 3930);
DISPLAY 0.617021 (-5965 3930);
PAINT ORANGE (-5965 3930);
FORCEPROP 1 LAST LOCATION C4E20
J 0
(-5925 4150);
DISPLAY 0.617021 (-5925 4150);
PAINT AQUA (-5925 4150);
FORCEPROP 1 LAST VALUE 0.1UF
J 0
(-5925 4100);
DISPLAY 0.617021 (-5925 4100);
PAINT SKYBLUE (-5925 4100);
FORCEPROP 1 LAST VOLTAGE 16V
J 0
(-5925 4050);
DISPLAY 0.617021 (-5925 4050);
PAINT SKYBLUE (-5925 4050);
FORCEPROP 1 LAST TOLERANCE 10%
J 0
(-5925 4000);
DISPLAY 0.617021 (-5925 4000);
PAINT SKYBLUE (-5925 4000);
FORCEPROP 1 LAST MATERIAL X7R
J 0
(-5925 3950);
DISPLAY 0.617021 (-5925 3950);
PAINT SKYBLUE (-5925 3950);
FORCEPROP 1 LAST PART_NUMBER A36096-030
J 0
(-5925 3900);
DISPLAY 0.617021 (-5925 3900);
PAINT BLUE (-5925 3900);
FORCEPROP 1 LAST PACK_TYPE 0402V
J 0
(-5925 3850);
DISPLAY 0.617021 (-5925 3850);
PAINT SKYBLUE (-5925 3850);
FORCEPROP 2 LAST CDS_LOCATION C4E20
J 0
(-5925 4150);
DISPLAY 0.617021 (-5925 4150);
PAINT AQUA (-5925 4150);
DISPLAY INVISIBLE (-5925 4150);
FORCEPROP 2 LAST CDS_SEC 1
J 0
(-5925 4200);
PAINT ORANGE (-5925 4200);
DISPLAY INVISIBLE (-5925 4200);
FORCEPROP 2 LAST CDS_LIB dev_discrete
J 0
(-5975 4050);
PAINT ORANGE (-5975 4050);
DISPLAY INVISIBLE (-5975 4050);
FORCEPROP 2 LAST SEC_TYPE 0402V
J 0
(-5925 4250);
DISPLAY 1.021277 (-5925 4250);
PAINT ORANGE (-5925 4250);
DISPLAY INVISIBLE (-5925 4250);
FORCEPROP 2 LAST SEC 1
J 0
(-5925 4250);
DISPLAY 0.680851 (-5925 4250);
PAINT MONO (-5925 4250);
DISPLAY INVISIBLE (-5925 4250);
FORCEPROP 1 LAST PATH I35
J 0
(-5925 4200);
DISPLAY 0.978723 (-5925 4200);
PAINT WHITE (-5925 4200);
DISPLAY INVISIBLE (-5925 4200);
FORCEPROP 2 LAST ROOM PVCCIN_CPU0_PWR_VR
J 0
(-5925 4200);
DISPLAY 1.361702 (-5925 4200);
PAINT ORANGE (-5925 4200);
DISPLAY INVISIBLE (-5925 4200);
FORCEADD CAP..1
(-6250 4075);
FORCEPROP 1 LAST TOLERANCE 10%
J 0
(-6200 4025);
DISPLAY 0.617021 (-6200 4025);
PAINT SKYBLUE (-6200 4025);
FORCEPROP 1 LAST VOLTAGE 16V
J 0
(-6200 4075);
DISPLAY 0.617021 (-6200 4075);
PAINT SKYBLUE (-6200 4075);
FORCEPROP 1 LASTPIN (-6250 3975) $PN 2
J 0
(-6240 3955);
DISPLAY 0.617021 (-6240 3955);
PAINT ORANGE (-6240 3955);
FORCEPROP 1 LASTPIN (-6250 4175) $PN 1
J 0
(-6240 4155);
DISPLAY 0.617021 (-6240 4155);
PAINT ORANGE (-6240 4155);
FORCEPROP 1 LAST MATERIAL X6S
J 0
(-6200 3975);
DISPLAY 0.617021 (-6200 3975);
PAINT SKYBLUE (-6200 3975);
FORCEPROP 1 LAST VALUE 1.0UF
J 0
(-6200 4125);
DISPLAY 0.617021 (-6200 4125);
PAINT SKYBLUE (-6200 4125);
FORCEPROP 1 LAST LOCATION C4E19
J 0
(-6200 4175);
DISPLAY 0.617021 (-6200 4175);
PAINT AQUA (-6200 4175);
FORCEPROP 1 LAST PACK_TYPE 0402
J 0
(-6200 3875);
DISPLAY 0.617021 (-6200 3875);
PAINT SKYBLUE (-6200 3875);
FORCEPROP 1 LAST PART_NUMBER D97712-011
J 0
(-6200 3925);
DISPLAY 0.617021 (-6200 3925);
PAINT BLUE (-6200 3925);
FORCEPROP 2 LAST CDS_LIB mstr_discrete
J 0
(-6250 4075);
PAINT ORANGE (-6250 4075);
DISPLAY INVISIBLE (-6250 4075);
FORCEPROP 2 LAST ROOM PVCCIN_CPU0_PWR_VR
J 0
(-6200 4225);
DISPLAY 1.361702 (-6200 4225);
PAINT ORANGE (-6200 4225);
DISPLAY INVISIBLE (-6200 4225);
FORCEPROP 1 LAST PATH I36
J 0
(-6200 4225);
DISPLAY 0.978723 (-6200 4225);
PAINT WHITE (-6200 4225);
DISPLAY INVISIBLE (-6200 4225);
FORCEPROP 2 LAST CDS_LOCATION C4E19
J 0
(-6200 4175);
DISPLAY 0.617021 (-6200 4175);
PAINT AQUA (-6200 4175);
DISPLAY INVISIBLE (-6200 4175);
FORCEPROP 2 LAST SEC 1
J 0
(-6200 4275);
DISPLAY 0.680851 (-6200 4275);
PAINT MONO (-6200 4275);
DISPLAY INVISIBLE (-6200 4275);
FORCEPROP 2 LAST SEC_TYPE 0402
J 0
(-6200 4275);
DISPLAY 1.021277 (-6200 4275);
PAINT ORANGE (-6200 4275);
DISPLAY INVISIBLE (-6200 4275);
FORCEADD CAP..1
(-6550 4075);
FORCEPROP 1 LAST TOLERANCE 10%
J 0
(-6500 4025);
DISPLAY 0.617021 (-6500 4025);
PAINT SKYBLUE (-6500 4025);
FORCEPROP 1 LAST VOLTAGE 16V
J 0
(-6500 4075);
DISPLAY 0.617021 (-6500 4075);
PAINT SKYBLUE (-6500 4075);
FORCEPROP 1 LAST PART_NUMBER C95333-007
J 0
(-6500 3925);
DISPLAY 0.617021 (-6500 3925);
PAINT BLUE (-6500 3925);
FORCEPROP 1 LAST MATERIAL X6S
J 0
(-6500 3975);
DISPLAY 0.617021 (-6500 3975);
PAINT SKYBLUE (-6500 3975);
FORCEPROP 1 LAST VALUE 10UF
J 0
(-6500 4125);
DISPLAY 0.617021 (-6500 4125);
PAINT SKYBLUE (-6500 4125);
FORCEPROP 1 LAST LOCATION C6R11
J 0
(-6500 4175);
DISPLAY 0.617021 (-6500 4175);
PAINT AQUA (-6500 4175);
FORCEPROP 1 LASTPIN (-6550 4175) $PN 1
J 0
(-6540 4155);
DISPLAY 0.617021 (-6540 4155);
PAINT ORANGE (-6540 4155);
FORCEPROP 1 LASTPIN (-6550 3975) $PN 2
J 0
(-6540 3955);
DISPLAY 0.617021 (-6540 3955);
PAINT ORANGE (-6540 3955);
FORCEPROP 1 LAST PACK_TYPE 0805
J 0
(-6500 3875);
DISPLAY 0.617021 (-6500 3875);
PAINT SKYBLUE (-6500 3875);
FORCEPROP 2 LAST SEC_TYPE 0805
J 0
(-6500 4275);
DISPLAY 1.021277 (-6500 4275);
PAINT ORANGE (-6500 4275);
DISPLAY INVISIBLE (-6500 4275);
FORCEPROP 2 LAST SEC 1
J 0
(-6500 4275);
DISPLAY 0.680851 (-6500 4275);
PAINT MONO (-6500 4275);
DISPLAY INVISIBLE (-6500 4275);
FORCEPROP 2 LAST CDS_LOCATION C6R11
J 0
(-6500 4175);
DISPLAY 0.617021 (-6500 4175);
PAINT AQUA (-6500 4175);
DISPLAY INVISIBLE (-6500 4175);
FORCEPROP 1 LAST PATH I37
J 0
(-6500 4225);
DISPLAY 0.978723 (-6500 4225);
PAINT WHITE (-6500 4225);
DISPLAY INVISIBLE (-6500 4225);
FORCEPROP 2 LAST ROOM PVCCIN_CPU0_PWR_VR
J 0
(-6500 4225);
DISPLAY 1.361702 (-6500 4225);
PAINT ORANGE (-6500 4225);
DISPLAY INVISIBLE (-6500 4225);
FORCEPROP 2 LAST CDS_LIB mstr_discrete
J 0
(-6550 4075);
PAINT ORANGE (-6550 4075);
DISPLAY INVISIBLE (-6550 4075);
FORCEADD CAP..1
(-6825 4075);
FORCEPROP 1 LAST TOLERANCE 10%
J 0
(-6775 4025);
DISPLAY 0.617021 (-6775 4025);
PAINT SKYBLUE (-6775 4025);
FORCEPROP 1 LAST VOLTAGE 16V
J 0
(-6775 4075);
DISPLAY 0.617021 (-6775 4075);
PAINT SKYBLUE (-6775 4075);
FORCEPROP 1 LAST PACK_TYPE 0805
J 0
(-6775 3875);
DISPLAY 0.617021 (-6775 3875);
PAINT SKYBLUE (-6775 3875);
FORCEPROP 1 LAST VALUE 10UF
J 0
(-6775 4125);
DISPLAY 0.617021 (-6775 4125);
PAINT SKYBLUE (-6775 4125);
FORCEPROP 1 LASTPIN (-6825 4175) $PN 1
J 0
(-6815 4155);
DISPLAY 0.617021 (-6815 4155);
PAINT ORANGE (-6815 4155);
FORCEPROP 1 LAST MATERIAL X6S
J 0
(-6775 3975);
DISPLAY 0.617021 (-6775 3975);
PAINT SKYBLUE (-6775 3975);
FORCEPROP 1 LASTPIN (-6825 3975) $PN 2
J 0
(-6815 3955);
DISPLAY 0.617021 (-6815 3955);
PAINT ORANGE (-6815 3955);
FORCEPROP 1 LAST LOCATION C6P13
J 0
(-6775 4175);
DISPLAY 0.617021 (-6775 4175);
PAINT AQUA (-6775 4175);
FORCEPROP 1 LAST PART_NUMBER C95333-007
J 0
(-6775 3925);
DISPLAY 0.617021 (-6775 3925);
PAINT BLUE (-6775 3925);
FORCEPROP 2 LAST CDS_LIB mstr_discrete
J 0
(-6825 4075);
PAINT ORANGE (-6825 4075);
DISPLAY INVISIBLE (-6825 4075);
FORCEPROP 1 LAST PATH I38
J 0
(-6775 4225);
DISPLAY 0.978723 (-6775 4225);
PAINT WHITE (-6775 4225);
DISPLAY INVISIBLE (-6775 4225);
FORCEPROP 2 LAST SEC_TYPE 0805
J 0
(-6775 4275);
DISPLAY 1.021277 (-6775 4275);
PAINT ORANGE (-6775 4275);
DISPLAY INVISIBLE (-6775 4275);
FORCEPROP 2 LAST CDS_LOCATION C6P13
J 0
(-6775 4175);
DISPLAY 0.617021 (-6775 4175);
PAINT AQUA (-6775 4175);
DISPLAY INVISIBLE (-6775 4175);
FORCEPROP 2 LAST SEC 1
J 0
(-6775 4275);
DISPLAY 0.680851 (-6775 4275);
PAINT MONO (-6775 4275);
DISPLAY INVISIBLE (-6775 4275);
FORCEPROP 2 LAST ROOM PVCCIN_CPU0_PWR_VR
J 0
(-6775 4225);
DISPLAY 1.361702 (-6775 4225);
PAINT ORANGE (-6775 4225);
DISPLAY INVISIBLE (-6775 4225);
FORCEADD PVCCIN_CPU0..1
(-650 3600);
FORCEPROP 3 LASTPIN (-650 3550) SIG_NAME PVCCIN_CPU0\g
J 0
(-640 3560);
DISPLAY 0.659574 (-640 3560);
PAINT MONO (-640 3560);
DISPLAY INVISIBLE (-640 3560);
FORCEPROP 1 LAST HDL_POWER PVCCIN_CPU0
J 1
(-650 3650);
DISPLAY 0.872340 (-650 3650);
PAINT GREEN (-650 3650);
DISPLAY INVISIBLE (-650 3650);
FORCEPROP 1 LAST BODY_TYPE PLUMBING
J 0
(-695 3557);
DISPLAY 0.340426 (-695 3557);
PAINT GREEN (-695 3557);
DISPLAY INVISIBLE (-695 3557);
FORCEPROP 2 LAST ROOM PVCCIN_CPU0_PWR_VR
J 0
(-650 3700);
DISPLAY 1.936170 (-650 3700);
PAINT ORANGE (-650 3700);
DISPLAY INVISIBLE (-650 3700);
FORCEPROP 1 LAST PATH I4
J 0
(-600 3625);
DISPLAY 0.872340 (-600 3625);
PAINT AQUA (-600 3625);
DISPLAY INVISIBLE (-600 3625);
FORCEPROP 2 LAST CDS_LIB mstr_symbols
J 0
(-650 3600);
PAINT ORANGE (-650 3600);
DISPLAY INVISIBLE (-650 3600);
FORCEPROP 2 LAST BOM_COST PROC_SOCKET 
J 0
(-650 3700);
DISPLAY 1.446809 (-650 3700);
PAINT MONO (-650 3700);
DISPLAY INVISIBLE (-650 3700);
FORCEPROP 1 LAST VOLTAGE 2.0V
J 0
(-695 3557);
DISPLAY 0.340426 (-695 3557);
PAINT SKYBLUE (-695 3557);
DISPLAY INVISIBLE (-695 3557);
FORCEADD OFFPAGE..1
(-6700 3700);
FORCEPROP 2 LASTPIN (-6650 3700) SIG_NAME VR_PVCCIN_CPU0_PWM1
J 0
(-6635 3710);
DISPLAY 0.617021 (-6635 3710);
PAINT ORANGE (-6635 3710);
FORCEPROP 2 LAST $XR0 201 
J 0
(-6952 3700);
DISPLAY 0.638298 (-6952 3700);
PAINT MONO (-6952 3700);
FORCEPROP 2 LAST PATH I40
J 0
(-6970 3750);
DISPLAY 1.021277 (-6970 3750);
PAINT ORANGE (-6970 3750);
DISPLAY INVISIBLE (-6970 3750);
FORCEPROP 2 LAST ROOM PVCCIN_CPU0_PWR_VR
J 0
(-7100 3775);
DISPLAY 1.936170 (-7100 3775);
PAINT ORANGE (-7100 3775);
DISPLAY INVISIBLE (-7100 3775);
FORCEPROP 2 LAST BOM_COST PROC_VRD_VCCIN_CPU0
J 0
(-6950 3750);
DISPLAY 1.446809 (-6950 3750);
PAINT MONO (-6950 3750);
DISPLAY INVISIBLE (-6950 3750);
FORCEPROP 2 LAST CDS_LIB mstr_standard
J 0
(-6700 3700);
DISPLAY 1.936170 (-6700 3700);
PAINT ORANGE (-6700 3700);
DISPLAY INVISIBLE (-6700 3700);
FORCEPROP 1 LAST OFFPAGE TRUE
J 0
(-6375 3575);
DISPLAY 1.680851 (-6375 3575);
PAINT GREEN (-6375 3575);
DISPLAY INVISIBLE (-6375 3575);
FORCEPROP 1 LAST COMMENT_BODY TRUE
J 0
(-6575 3600);
DISPLAY 1.680851 (-6575 3600);
PAINT GREEN (-6575 3600);
DISPLAY INVISIBLE (-6575 3600);
FORCEADD VCC_CORE..1
(-6600 4500);
FORCEPROP 3 LASTPIN (-6600 4450) SIG_NAME VR_FET_SW_P12V_STBY_PVCCIN_CPU0\g
J 0
(-6590 4460);
DISPLAY 0.659574 (-6590 4460);
PAINT MONO (-6590 4460);
DISPLAY INVISIBLE (-6590 4460);
FORCEPROP 1 LAST HDL_POWER VR_FET_SW_P12V_STBY_PVCCIN_CPU0
J 1
(-6550 4550);
DISPLAY 0.617021 (-6550 4550);
PAINT GREEN (-6550 4550);
FORCEPROP 1 LAST PATH I41
J 0
(-6550 4525);
DISPLAY 0.872340 (-6550 4525);
PAINT AQUA (-6550 4525);
DISPLAY INVISIBLE (-6550 4525);
FORCEPROP 2 LAST CDS_LIB mstr_symbols
J 0
(-6600 4500);
DISPLAY 1.936170 (-6600 4500);
PAINT ORANGE (-6600 4500);
DISPLAY INVISIBLE (-6600 4500);
FORCEADD CAP..1
(-7100 4075);
FORCEPROP 1 LAST PACK_TYPE 0805
J 0
(-7050 3875);
DISPLAY 0.617021 (-7050 3875);
PAINT SKYBLUE (-7050 3875);
FORCEPROP 1 LAST MATERIAL X6S
J 0
(-7050 3975);
DISPLAY 0.617021 (-7050 3975);
PAINT SKYBLUE (-7050 3975);
FORCEPROP 1 LAST LOCATION C6R13
J 0
(-7050 4175);
DISPLAY 0.617021 (-7050 4175);
PAINT AQUA (-7050 4175);
FORCEPROP 1 LASTPIN (-7100 4175) $PN 1
J 0
(-7090 4155);
DISPLAY 0.617021 (-7090 4155);
PAINT ORANGE (-7090 4155);
FORCEPROP 1 LAST PART_NUMBER C95333-007
J 0
(-7050 3925);
DISPLAY 0.617021 (-7050 3925);
PAINT BLUE (-7050 3925);
FORCEPROP 1 LAST VOLTAGE 16V
J 0
(-7050 4075);
DISPLAY 0.617021 (-7050 4075);
PAINT SKYBLUE (-7050 4075);
FORCEPROP 1 LAST VALUE 10UF
J 0
(-7050 4125);
DISPLAY 0.617021 (-7050 4125);
PAINT SKYBLUE (-7050 4125);
FORCEPROP 1 LASTPIN (-7100 3975) $PN 2
J 0
(-7090 3955);
DISPLAY 0.617021 (-7090 3955);
PAINT ORANGE (-7090 3955);
FORCEPROP 1 LAST TOLERANCE 10%
J 0
(-7050 4025);
DISPLAY 0.617021 (-7050 4025);
PAINT SKYBLUE (-7050 4025);
FORCEPROP 2 LAST CDS_LIB mstr_discrete
J 0
(-7100 4075);
PAINT ORANGE (-7100 4075);
DISPLAY INVISIBLE (-7100 4075);
FORCEPROP 2 LAST ROOM PVCCIN_CPU0_PWR_VR
J 0
(-7050 4225);
DISPLAY 1.361702 (-7050 4225);
PAINT ORANGE (-7050 4225);
DISPLAY INVISIBLE (-7050 4225);
FORCEPROP 1 LAST PATH I42
J 0
(-7050 4225);
DISPLAY 0.978723 (-7050 4225);
PAINT WHITE (-7050 4225);
DISPLAY INVISIBLE (-7050 4225);
FORCEPROP 2 LAST CDS_LOCATION C6R13
J 0
(-7050 4175);
DISPLAY 0.617021 (-7050 4175);
PAINT AQUA (-7050 4175);
DISPLAY INVISIBLE (-7050 4175);
FORCEPROP 2 LAST SEC 1
J 0
(-7050 4275);
DISPLAY 0.680851 (-7050 4275);
PAINT MONO (-7050 4275);
DISPLAY INVISIBLE (-7050 4275);
FORCEPROP 2 LAST SEC_TYPE 0805
J 0
(-7050 4275);
DISPLAY 1.021277 (-7050 4275);
PAINT ORANGE (-7050 4275);
DISPLAY INVISIBLE (-7050 4275);
FORCEADD GND..1
(-7100 3525);
FORCEPROP 3 LASTPIN (-7100 3575) SIG_NAME GND\g
J 0
(-7090 3585);
DISPLAY 0.659574 (-7090 3585);
PAINT MONO (-7090 3585);
DISPLAY INVISIBLE (-7090 3585);
FORCEPROP 2 LAST ROOM PVCCIN_CPU0_PWR_VR
J 0
(-7650 3600);
DISPLAY 1.936170 (-7650 3600);
PAINT ORANGE (-7650 3600);
DISPLAY INVISIBLE (-7650 3600);
FORCEPROP 1 LAST VOLTAGE 0
J 0
(-7100 3525);
PAINT SKYBLUE (-7100 3525);
DISPLAY INVISIBLE (-7100 3525);
FORCEPROP 2 LAST CDS_LIB mstr_symbols
J 0
(-7100 3525);
DISPLAY 1.936170 (-7100 3525);
PAINT ORANGE (-7100 3525);
DISPLAY INVISIBLE (-7100 3525);
FORCEPROP 2 LAST BOM_COST PROC_VRD_VCCIN_CPU0
J 0
(-7475 3600);
DISPLAY 1.446809 (-7475 3600);
PAINT MONO (-7475 3600);
DISPLAY INVISIBLE (-7475 3600);
FORCEPROP 1 LAST PATH I43
J 0
(-7025 3525);
DISPLAY 0.872340 (-7025 3525);
PAINT AQUA (-7025 3525);
DISPLAY INVISIBLE (-7025 3525);
FORCEPROP 1 LAST SIZE 1B
J 0
(-7025 3475);
DISPLAY 1.723404 (-7025 3475);
PAINT GREEN (-7025 3475);
DISPLAY INVISIBLE (-7025 3475);
FORCEPROP 1 LAST BODY_TYPE PLUMBING
J 0
(-7145 3482);
DISPLAY 0.340426 (-7145 3482);
PAINT GREEN (-7145 3482);
DISPLAY INVISIBLE (-7145 3482);
FORCEPROP 1 LAST HDL_POWER GND
J 0
(-7100 3675);
DISPLAY 1.723404 (-7100 3675);
PAINT GREEN (-7100 3675);
DISPLAY INVISIBLE (-7100 3675);
FORCEADD VCC_CORE..1
(-6725 1875);
FORCEPROP 3 LASTPIN (-6725 1825) SIG_NAME VR_FET_SW_P12V_STBY_PVCCIN_CPU0\g
J 0
(-6715 1835);
DISPLAY 0.659574 (-6715 1835);
PAINT MONO (-6715 1835);
DISPLAY INVISIBLE (-6715 1835);
FORCEPROP 1 LAST HDL_POWER VR_FET_SW_P12V_STBY_PVCCIN_CPU0
J 1
(-6675 1925);
DISPLAY 0.617021 (-6675 1925);
PAINT GREEN (-6675 1925);
FORCEPROP 2 LAST CDS_LIB mstr_symbols
J 0
(-6725 1875);
PAINT ORANGE (-6725 1875);
DISPLAY INVISIBLE (-6725 1875);
FORCEPROP 1 LAST PATH I44
J 0
(-6675 1900);
DISPLAY 0.872340 (-6675 1900);
PAINT AQUA (-6675 1900);
DISPLAY INVISIBLE (-6675 1900);
FORCEADD CAP..1
(-5775 1475);
FORCEPROP 1 LAST LOCATION C4E26
J 0
(-5725 1575);
DISPLAY 0.617021 (-5725 1575);
PAINT AQUA (-5725 1575);
FORCEPROP 1 LAST PART_NUMBER D97712-011
J 0
(-5725 1325);
DISPLAY 0.617021 (-5725 1325);
PAINT BLUE (-5725 1325);
FORCEPROP 1 LAST PACK_TYPE 0402
J 0
(-5725 1275);
DISPLAY 0.617021 (-5725 1275);
PAINT SKYBLUE (-5725 1275);
FORCEPROP 1 LAST VALUE 1.0UF
J 0
(-5725 1525);
DISPLAY 0.617021 (-5725 1525);
PAINT SKYBLUE (-5725 1525);
FORCEPROP 1 LAST VOLTAGE 16V
J 0
(-5725 1475);
DISPLAY 0.617021 (-5725 1475);
PAINT SKYBLUE (-5725 1475);
FORCEPROP 1 LAST MATERIAL X6S
J 0
(-5725 1375);
DISPLAY 0.617021 (-5725 1375);
PAINT SKYBLUE (-5725 1375);
FORCEPROP 1 LAST TOLERANCE 10%
J 0
(-5725 1425);
DISPLAY 0.617021 (-5725 1425);
PAINT SKYBLUE (-5725 1425);
FORCEPROP 1 LASTPIN (-5775 1575) $PN 1
J 0
(-5765 1555);
DISPLAY 0.617021 (-5765 1555);
PAINT ORANGE (-5765 1555);
FORCEPROP 1 LASTPIN (-5775 1375) $PN 2
J 0
(-5765 1355);
DISPLAY 0.617021 (-5765 1355);
PAINT ORANGE (-5765 1355);
FORCEPROP 2 LAST ROOM PVCCIN_CPU0_PWR_VR
J 0
(-5725 1625);
DISPLAY 1.361702 (-5725 1625);
PAINT ORANGE (-5725 1625);
DISPLAY INVISIBLE (-5725 1625);
FORCEPROP 1 LAST PATH I45
J 0
(-5725 1625);
DISPLAY 0.978723 (-5725 1625);
PAINT WHITE (-5725 1625);
DISPLAY INVISIBLE (-5725 1625);
FORCEPROP 2 LAST SEC 1
J 0
(-5725 1675);
DISPLAY 0.680851 (-5725 1675);
PAINT MONO (-5725 1675);
DISPLAY INVISIBLE (-5725 1675);
FORCEPROP 2 LAST SEC_TYPE 0402
J 0
(-5725 1675);
DISPLAY 1.021277 (-5725 1675);
PAINT ORANGE (-5725 1675);
DISPLAY INVISIBLE (-5725 1675);
FORCEPROP 2 LAST CDS_LIB mstr_discrete
J 0
(-5775 1475);
PAINT ORANGE (-5775 1475);
DISPLAY INVISIBLE (-5775 1475);
FORCEADD CAP_A..1
(-6050 1475);
FORCEPROP 1 LAST PACK_TYPE 0402V
J 0
(-6000 1275);
DISPLAY 0.617021 (-6000 1275);
PAINT SKYBLUE (-6000 1275);
FORCEPROP 1 LAST PART_NUMBER A36096-030
J 0
(-6000 1325);
DISPLAY 0.617021 (-6000 1325);
PAINT BLUE (-6000 1325);
FORCEPROP 1 LAST LOCATION C4D49
J 0
(-6000 1575);
DISPLAY 0.617021 (-6000 1575);
PAINT AQUA (-6000 1575);
FORCEPROP 1 LAST VALUE 0.1UF
J 0
(-6000 1525);
DISPLAY 0.617021 (-6000 1525);
PAINT SKYBLUE (-6000 1525);
FORCEPROP 1 LAST TOLERANCE 10%
J 0
(-6000 1425);
DISPLAY 0.617021 (-6000 1425);
PAINT SKYBLUE (-6000 1425);
FORCEPROP 1 LAST VOLTAGE 16V
J 0
(-6000 1475);
DISPLAY 0.617021 (-6000 1475);
PAINT SKYBLUE (-6000 1475);
FORCEPROP 1 LAST MATERIAL X7R
J 0
(-6000 1375);
DISPLAY 0.617021 (-6000 1375);
PAINT SKYBLUE (-6000 1375);
FORCEPROP 1 LASTPIN (-6050 1575) $PN 1
J 0
(-6040 1555);
DISPLAY 0.617021 (-6040 1555);
PAINT ORANGE (-6040 1555);
FORCEPROP 1 LASTPIN (-6050 1375) $PN 2
J 0
(-6040 1355);
DISPLAY 0.617021 (-6040 1355);
PAINT ORANGE (-6040 1355);
FORCEPROP 2 LAST SEC 1
J 0
(-6000 1675);
DISPLAY 0.680851 (-6000 1675);
PAINT MONO (-6000 1675);
DISPLAY INVISIBLE (-6000 1675);
FORCEPROP 2 LAST SEC_TYPE 0402V
J 0
(-6000 1675);
DISPLAY 1.021277 (-6000 1675);
PAINT ORANGE (-6000 1675);
DISPLAY INVISIBLE (-6000 1675);
FORCEPROP 2 LAST CDS_SEC 1
J 0
(-6000 1625);
PAINT ORANGE (-6000 1625);
DISPLAY INVISIBLE (-6000 1625);
FORCEPROP 2 LAST ROOM PVCCIN_CPU0_PWR_VR
J 0
(-6000 1625);
DISPLAY 1.361702 (-6000 1625);
PAINT ORANGE (-6000 1625);
DISPLAY INVISIBLE (-6000 1625);
FORCEPROP 1 LAST PATH I46
J 0
(-6000 1625);
DISPLAY 0.978723 (-6000 1625);
PAINT WHITE (-6000 1625);
DISPLAY INVISIBLE (-6000 1625);
FORCEPROP 2 LAST CDS_LIB dev_discrete
J 0
(-6050 1475);
PAINT ORANGE (-6050 1475);
DISPLAY INVISIBLE (-6050 1475);
FORCEADD CAP..1
(-6350 1475);
FORCEPROP 1 LAST PART_NUMBER D97712-011
J 0
(-6300 1325);
DISPLAY 0.617021 (-6300 1325);
PAINT BLUE (-6300 1325);
FORCEPROP 1 LAST MATERIAL X6S
J 0
(-6300 1375);
DISPLAY 0.617021 (-6300 1375);
PAINT SKYBLUE (-6300 1375);
FORCEPROP 1 LASTPIN (-6350 1375) $PN 2
J 0
(-6340 1355);
DISPLAY 0.617021 (-6340 1355);
PAINT ORANGE (-6340 1355);
FORCEPROP 1 LAST PACK_TYPE 0402
J 0
(-6300 1275);
DISPLAY 0.617021 (-6300 1275);
PAINT SKYBLUE (-6300 1275);
FORCEPROP 1 LAST TOLERANCE 10%
J 0
(-6300 1425);
DISPLAY 0.617021 (-6300 1425);
PAINT SKYBLUE (-6300 1425);
FORCEPROP 1 LAST LOCATION C4D48
J 0
(-6300 1575);
DISPLAY 0.617021 (-6300 1575);
PAINT AQUA (-6300 1575);
FORCEPROP 1 LAST VOLTAGE 16V
J 0
(-6300 1475);
DISPLAY 0.617021 (-6300 1475);
PAINT SKYBLUE (-6300 1475);
FORCEPROP 1 LASTPIN (-6350 1575) $PN 1
J 0
(-6340 1555);
DISPLAY 0.617021 (-6340 1555);
PAINT ORANGE (-6340 1555);
FORCEPROP 1 LAST VALUE 1.0UF
J 0
(-6300 1525);
DISPLAY 0.617021 (-6300 1525);
PAINT SKYBLUE (-6300 1525);
FORCEPROP 2 LAST ROOM PVCCIN_CPU0_PWR_VR
J 0
(-6300 1625);
DISPLAY 1.361702 (-6300 1625);
PAINT ORANGE (-6300 1625);
DISPLAY INVISIBLE (-6300 1625);
FORCEPROP 1 LAST PATH I47
J 0
(-6300 1625);
DISPLAY 0.978723 (-6300 1625);
PAINT WHITE (-6300 1625);
DISPLAY INVISIBLE (-6300 1625);
FORCEPROP 2 LAST SEC 1
J 0
(-6300 1675);
DISPLAY 0.680851 (-6300 1675);
PAINT MONO (-6300 1675);
DISPLAY INVISIBLE (-6300 1675);
FORCEPROP 2 LAST SEC_TYPE 0402
J 0
(-6300 1675);
DISPLAY 1.021277 (-6300 1675);
PAINT ORANGE (-6300 1675);
DISPLAY INVISIBLE (-6300 1675);
FORCEPROP 2 LAST CDS_LIB mstr_discrete
J 0
(-6350 1475);
PAINT ORANGE (-6350 1475);
DISPLAY INVISIBLE (-6350 1475);
FORCEADD CAP..1
(-6625 1475);
FORCEPROP 1 LAST PART_NUMBER C95333-007
J 0
(-6575 1325);
DISPLAY 0.617021 (-6575 1325);
PAINT BLUE (-6575 1325);
FORCEPROP 1 LAST PACK_TYPE 0805
J 0
(-6575 1275);
DISPLAY 0.617021 (-6575 1275);
PAINT SKYBLUE (-6575 1275);
FORCEPROP 1 LASTPIN (-6625 1375) $PN 2
J 0
(-6615 1355);
DISPLAY 0.617021 (-6615 1355);
PAINT ORANGE (-6615 1355);
FORCEPROP 1 LAST MATERIAL X6S
J 0
(-6575 1375);
DISPLAY 0.617021 (-6575 1375);
PAINT SKYBLUE (-6575 1375);
FORCEPROP 1 LAST VOLTAGE 16V
J 0
(-6575 1475);
DISPLAY 0.617021 (-6575 1475);
PAINT SKYBLUE (-6575 1475);
FORCEPROP 1 LAST LOCATION C6R4
J 0
(-6575 1575);
DISPLAY 0.617021 (-6575 1575);
PAINT AQUA (-6575 1575);
FORCEPROP 1 LASTPIN (-6625 1575) $PN 1
J 0
(-6615 1555);
DISPLAY 0.617021 (-6615 1555);
PAINT ORANGE (-6615 1555);
FORCEPROP 1 LAST VALUE 10UF
J 0
(-6575 1525);
DISPLAY 0.617021 (-6575 1525);
PAINT SKYBLUE (-6575 1525);
FORCEPROP 1 LAST TOLERANCE 10%
J 0
(-6575 1425);
DISPLAY 0.617021 (-6575 1425);
PAINT SKYBLUE (-6575 1425);
FORCEPROP 2 LAST ROOM PVCCIN_CPU0_PWR_VR
J 0
(-6575 1625);
DISPLAY 1.361702 (-6575 1625);
PAINT ORANGE (-6575 1625);
DISPLAY INVISIBLE (-6575 1625);
FORCEPROP 1 LAST PATH I48
J 0
(-6575 1625);
DISPLAY 0.978723 (-6575 1625);
PAINT WHITE (-6575 1625);
DISPLAY INVISIBLE (-6575 1625);
FORCEPROP 2 LAST SEC 1
J 0
(-6575 1675);
DISPLAY 0.680851 (-6575 1675);
PAINT MONO (-6575 1675);
DISPLAY INVISIBLE (-6575 1675);
FORCEPROP 2 LAST SEC_TYPE 0805
J 0
(-6575 1675);
DISPLAY 1.021277 (-6575 1675);
PAINT ORANGE (-6575 1675);
DISPLAY INVISIBLE (-6575 1675);
FORCEPROP 2 LAST CDS_LOCATION C6R4
J 0
(-6575 1575);
DISPLAY 0.617021 (-6575 1575);
PAINT AQUA (-6575 1575);
DISPLAY INVISIBLE (-6575 1575);
FORCEPROP 2 LAST CDS_LIB mstr_discrete
J 0
(-6625 1475);
PAINT ORANGE (-6625 1475);
DISPLAY INVISIBLE (-6625 1475);
FORCEADD CAP..1
(-6900 1475);
FORCEPROP 1 LAST PART_NUMBER C95333-007
J 0
(-6850 1325);
DISPLAY 0.617021 (-6850 1325);
PAINT BLUE (-6850 1325);
FORCEPROP 1 LAST VOLTAGE 16V
J 0
(-6850 1475);
DISPLAY 0.617021 (-6850 1475);
PAINT SKYBLUE (-6850 1475);
FORCEPROP 1 LAST PACK_TYPE 0805
J 0
(-6850 1275);
DISPLAY 0.617021 (-6850 1275);
PAINT SKYBLUE (-6850 1275);
FORCEPROP 1 LAST LOCATION C6P22
J 0
(-6850 1575);
DISPLAY 0.617021 (-6850 1575);
PAINT AQUA (-6850 1575);
FORCEPROP 1 LAST MATERIAL X6S
J 0
(-6850 1375);
DISPLAY 0.617021 (-6850 1375);
PAINT SKYBLUE (-6850 1375);
FORCEPROP 1 LASTPIN (-6900 1575) $PN 1
J 0
(-6890 1555);
DISPLAY 0.617021 (-6890 1555);
PAINT ORANGE (-6890 1555);
FORCEPROP 1 LAST VALUE 10UF
J 0
(-6850 1525);
DISPLAY 0.617021 (-6850 1525);
PAINT SKYBLUE (-6850 1525);
FORCEPROP 1 LASTPIN (-6900 1375) $PN 2
J 0
(-6890 1355);
DISPLAY 0.617021 (-6890 1355);
PAINT ORANGE (-6890 1355);
FORCEPROP 1 LAST TOLERANCE 10%
J 0
(-6850 1425);
DISPLAY 0.617021 (-6850 1425);
PAINT SKYBLUE (-6850 1425);
FORCEPROP 2 LAST ROOM PVCCIN_CPU0_PWR_VR
J 0
(-6850 1625);
DISPLAY 1.361702 (-6850 1625);
PAINT ORANGE (-6850 1625);
DISPLAY INVISIBLE (-6850 1625);
FORCEPROP 1 LAST PATH I49
J 0
(-6850 1625);
DISPLAY 0.978723 (-6850 1625);
PAINT WHITE (-6850 1625);
DISPLAY INVISIBLE (-6850 1625);
FORCEPROP 2 LAST CDS_LOCATION C6P22
J 0
(-6850 1575);
DISPLAY 0.617021 (-6850 1575);
PAINT AQUA (-6850 1575);
DISPLAY INVISIBLE (-6850 1575);
FORCEPROP 2 LAST SEC 1
J 0
(-6850 1675);
DISPLAY 0.680851 (-6850 1675);
PAINT MONO (-6850 1675);
DISPLAY INVISIBLE (-6850 1675);
FORCEPROP 2 LAST SEC_TYPE 0805
J 0
(-6850 1675);
DISPLAY 1.021277 (-6850 1675);
PAINT ORANGE (-6850 1675);
DISPLAY INVISIBLE (-6850 1675);
FORCEPROP 2 LAST CDS_LIB mstr_discrete
J 0
(-6900 1475);
PAINT ORANGE (-6900 1475);
DISPLAY INVISIBLE (-6900 1475);
FORCEADD OFFPAGE..1
(-6725 1075);
FORCEPROP 2 LAST $XR0 201 
J 0
(-6977 1075);
DISPLAY 0.638298 (-6977 1075);
PAINT MONO (-6977 1075);
FORCEPROP 2 LAST BOM_COST PROC_VRD_VCCIN_CPU0
J 0
(-6975 1125);
DISPLAY 1.446809 (-6975 1125);
PAINT MONO (-6975 1125);
DISPLAY INVISIBLE (-6975 1125);
FORCEPROP 2 LAST ROOM PVCCIN_CPU0_PWR_VR
J 0
(-7125 1150);
DISPLAY 1.936170 (-7125 1150);
PAINT ORANGE (-7125 1150);
DISPLAY INVISIBLE (-7125 1150);
FORCEPROP 2 LAST CDS_LIB mstr_standard
J 0
(-6725 1075);
PAINT ORANGE (-6725 1075);
DISPLAY INVISIBLE (-6725 1075);
FORCEPROP 2 LAST PATH I50
J 0
(-6670 1150);
DISPLAY 1.021277 (-6670 1150);
PAINT ORANGE (-6670 1150);
DISPLAY INVISIBLE (-6670 1150);
FORCEPROP 1 LAST OFFPAGE TRUE
J 0
(-6400 950);
DISPLAY 1.680851 (-6400 950);
PAINT GREEN (-6400 950);
DISPLAY INVISIBLE (-6400 950);
FORCEPROP 1 LAST COMMENT_BODY TRUE
J 0
(-6600 975);
DISPLAY 1.680851 (-6600 975);
PAINT GREEN (-6600 975);
DISPLAY INVISIBLE (-6600 975);
FORCEADD CAP..1
(-7175 1475);
FORCEPROP 1 LAST LOCATION C6N8
J 0
(-7125 1575);
DISPLAY 0.617021 (-7125 1575);
PAINT AQUA (-7125 1575);
FORCEPROP 1 LAST VOLTAGE 16V
J 0
(-7125 1475);
DISPLAY 0.617021 (-7125 1475);
PAINT SKYBLUE (-7125 1475);
FORCEPROP 1 LAST TOLERANCE 10%
J 0
(-7125 1425);
DISPLAY 0.617021 (-7125 1425);
PAINT SKYBLUE (-7125 1425);
FORCEPROP 1 LAST MATERIAL X6S
J 0
(-7125 1375);
DISPLAY 0.617021 (-7125 1375);
PAINT SKYBLUE (-7125 1375);
FORCEPROP 1 LAST PART_NUMBER C95333-007
J 0
(-7125 1325);
DISPLAY 0.617021 (-7125 1325);
PAINT BLUE (-7125 1325);
FORCEPROP 1 LAST PACK_TYPE 0805
J 0
(-7125 1275);
DISPLAY 0.617021 (-7125 1275);
PAINT SKYBLUE (-7125 1275);
FORCEPROP 1 LASTPIN (-7175 1375) $PN 2
J 0
(-7165 1355);
DISPLAY 0.617021 (-7165 1355);
PAINT ORANGE (-7165 1355);
FORCEPROP 1 LAST VALUE 10UF
J 0
(-7125 1525);
DISPLAY 0.617021 (-7125 1525);
PAINT SKYBLUE (-7125 1525);
FORCEPROP 1 LASTPIN (-7175 1575) $PN 1
J 0
(-7165 1555);
DISPLAY 0.617021 (-7165 1555);
PAINT ORANGE (-7165 1555);
FORCEPROP 2 LAST SEC_TYPE 0805
J 0
(-7125 1675);
DISPLAY 1.021277 (-7125 1675);
PAINT ORANGE (-7125 1675);
DISPLAY INVISIBLE (-7125 1675);
FORCEPROP 2 LAST SEC 1
J 0
(-7125 1675);
DISPLAY 0.680851 (-7125 1675);
PAINT MONO (-7125 1675);
DISPLAY INVISIBLE (-7125 1675);
FORCEPROP 1 LAST PATH I51
J 0
(-7125 1625);
DISPLAY 0.978723 (-7125 1625);
PAINT WHITE (-7125 1625);
DISPLAY INVISIBLE (-7125 1625);
FORCEPROP 2 LAST ROOM PVCCIN_CPU0_PWR_VR
J 0
(-7125 1625);
DISPLAY 1.361702 (-7125 1625);
PAINT ORANGE (-7125 1625);
DISPLAY INVISIBLE (-7125 1625);
FORCEPROP 2 LAST CDS_LOCATION C6N8
J 0
(-7125 1575);
DISPLAY 0.617021 (-7125 1575);
PAINT AQUA (-7125 1575);
DISPLAY INVISIBLE (-7125 1575);
FORCEPROP 2 LAST CDS_LIB mstr_discrete
J 0
(-7175 1475);
PAINT ORANGE (-7175 1475);
DISPLAY INVISIBLE (-7175 1475);
FORCEADD GND..1
(-7175 1050);
FORCEPROP 3 LASTPIN (-7175 1100) SIG_NAME GND\g
J 0
(-7165 1110);
DISPLAY 0.659574 (-7165 1110);
PAINT MONO (-7165 1110);
DISPLAY INVISIBLE (-7165 1110);
FORCEPROP 1 LAST PATH I52
J 0
(-7100 1050);
DISPLAY 0.872340 (-7100 1050);
PAINT AQUA (-7100 1050);
DISPLAY INVISIBLE (-7100 1050);
FORCEPROP 1 LAST SIZE 1B
J 0
(-7100 1000);
DISPLAY 1.723404 (-7100 1000);
PAINT GREEN (-7100 1000);
DISPLAY INVISIBLE (-7100 1000);
FORCEPROP 1 LAST VOLTAGE 0
J 0
(-7175 1050);
PAINT SKYBLUE (-7175 1050);
DISPLAY INVISIBLE (-7175 1050);
FORCEPROP 2 LAST CDS_LIB mstr_symbols
J 0
(-7175 1050);
PAINT ORANGE (-7175 1050);
DISPLAY INVISIBLE (-7175 1050);
FORCEPROP 2 LAST BOM_COST PROC_VRD_VCCIN_CPU0
J 0
(-7550 1125);
DISPLAY 1.446809 (-7550 1125);
PAINT MONO (-7550 1125);
DISPLAY INVISIBLE (-7550 1125);
FORCEPROP 2 LAST ROOM PVCCIN_CPU0_PWR_VR
J 0
(-7725 1125);
DISPLAY 1.936170 (-7725 1125);
PAINT ORANGE (-7725 1125);
DISPLAY INVISIBLE (-7725 1125);
FORCEPROP 1 LAST BODY_TYPE PLUMBING
J 0
(-7220 1007);
DISPLAY 0.340426 (-7220 1007);
PAINT GREEN (-7220 1007);
DISPLAY INVISIBLE (-7220 1007);
FORCEPROP 1 LAST HDL_POWER GND
J 0
(-7175 1200);
DISPLAY 1.723404 (-7175 1200);
PAINT GREEN (-7175 1200);
DISPLAY INVISIBLE (-7175 1200);
FORCEADD P5V_STBY..1
(-4700 2100);
FORCEPROP 3 LASTPIN (-4700 2050) SIG_NAME P5V_STBY\g
J 0
(-4690 2060);
DISPLAY 0.659574 (-4690 2060);
PAINT MONO (-4690 2060);
DISPLAY INVISIBLE (-4690 2060);
FORCEPROP 1 LAST PATH I59
J 0
(-4655 2102);
DISPLAY 0.340426 (-4655 2102);
PAINT GREEN (-4655 2102);
DISPLAY INVISIBLE (-4655 2102);
FORCEPROP 1 LAST SIZE 1B
J 0
(-4655 2122);
DISPLAY 0.340426 (-4655 2122);
PAINT GREEN (-4655 2122);
DISPLAY INVISIBLE (-4655 2122);
FORCEPROP 2 LAST CDS_LIB mstr_symbols
J 0
(-4700 2100);
PAINT ORANGE (-4700 2100);
DISPLAY INVISIBLE (-4700 2100);
FORCEPROP 1 LAST VOLTAGE 5.0V
J 0
(-4745 2057);
DISPLAY 0.340426 (-4745 2057);
PAINT SKYBLUE (-4745 2057);
DISPLAY INVISIBLE (-4745 2057);
FORCEPROP 1 LAST BODY_TYPE PLUMBING
J 0
(-4745 2057);
DISPLAY 0.340426 (-4745 2057);
PAINT GREEN (-4745 2057);
DISPLAY INVISIBLE (-4745 2057);
FORCEPROP 1 LAST HDL_POWER P5V_STBY
J 0
(-5000 1975);
DISPLAY 0.872340 (-5000 1975);
PAINT ORANGE (-5000 1975);
DISPLAY INVISIBLE (-5000 1975);
FORCEADD P5V_STBY..1
(-4675 4750);
FORCEPROP 3 LASTPIN (-4675 4700) SIG_NAME P5V_STBY\g
J 0
(-4665 4710);
DISPLAY 0.659574 (-4665 4710);
PAINT MONO (-4665 4710);
DISPLAY INVISIBLE (-4665 4710);
FORCEPROP 1 LAST VOLTAGE 5.0V
J 0
(-4720 4707);
DISPLAY 0.340426 (-4720 4707);
PAINT SKYBLUE (-4720 4707);
DISPLAY INVISIBLE (-4720 4707);
FORCEPROP 2 LAST CDS_LIB mstr_symbols
J 0
(-4675 4750);
PAINT ORANGE (-4675 4750);
DISPLAY INVISIBLE (-4675 4750);
FORCEPROP 1 LAST SIZE 1B
J 0
(-4630 4772);
DISPLAY 0.340426 (-4630 4772);
PAINT GREEN (-4630 4772);
DISPLAY INVISIBLE (-4630 4772);
FORCEPROP 1 LAST PATH I60
J 0
(-4630 4752);
DISPLAY 0.340426 (-4630 4752);
PAINT GREEN (-4630 4752);
DISPLAY INVISIBLE (-4630 4752);
FORCEPROP 1 LAST BODY_TYPE PLUMBING
J 0
(-4720 4707);
DISPLAY 0.340426 (-4720 4707);
PAINT GREEN (-4720 4707);
DISPLAY INVISIBLE (-4720 4707);
FORCEPROP 1 LAST HDL_POWER P5V_STBY
J 0
(-4975 4625);
DISPLAY 0.872340 (-4975 4625);
PAINT ORANGE (-4975 4625);
DISPLAY INVISIBLE (-4975 4625);
FORCEADD CAP_A..1
(-650 3300);
FORCEPROP 0 LAST GROUP PWR_MLCC_CAP
J 0
(-602 3102);
DISPLAY 0.638298 (-602 3102);
PAINT BROWN (-602 3102);
DISPLAY BOTH (-602 3102);
FORCEPROP 1 LAST PACK_TYPE 0603V
J 0
(-600 3150);
DISPLAY 0.617021 (-600 3150);
PAINT SKYBLUE (-600 3150);
FORCEPROP 1 LAST LOCATION C4E3
J 0
(-600 3450);
DISPLAY 0.617021 (-600 3450);
PAINT AQUA (-600 3450);
FORCEPROP 1 LAST VOLTAGE 4V
J 0
(-600 3350);
DISPLAY 0.617021 (-600 3350);
PAINT SKYBLUE (-600 3350);
FORCEPROP 1 LAST TOLERANCE 20%
J 0
(-600 3300);
DISPLAY 0.617021 (-600 3300);
PAINT SKYBLUE (-600 3300);
FORCEPROP 1 LAST MATERIAL X6S
J 0
(-600 3250);
DISPLAY 0.617021 (-600 3250);
PAINT SKYBLUE (-600 3250);
FORCEPROP 1 LAST PART_NUMBER E15431-004
J 0
(-600 3200);
DISPLAY 0.617021 (-600 3200);
PAINT BLUE (-600 3200);
FORCEPROP 1 LASTPIN (-650 3200) $PN 2
J 0
(-640 3180);
DISPLAY 0.617021 (-640 3180);
PAINT ORANGE (-640 3180);
FORCEPROP 1 LASTPIN (-650 3400) $PN 1
J 0
(-640 3380);
DISPLAY 0.617021 (-640 3380);
PAINT ORANGE (-640 3380);
FORCEPROP 1 LAST VALUE 22.0UF
J 0
(-600 3400);
DISPLAY 0.617021 (-600 3400);
PAINT SKYBLUE (-600 3400);
FORCEPROP 1 LAST PATH I61
J 0
(-600 3450);
DISPLAY 0.978723 (-600 3450);
PAINT WHITE (-600 3450);
DISPLAY INVISIBLE (-600 3450);
FORCEPROP 2 LAST CDS_SEC 1
J 0
(-600 3450);
PAINT ORANGE (-600 3450);
DISPLAY INVISIBLE (-600 3450);
FORCEPROP 2 LAST CDS_LOCATION C4E3
J 0
(-600 3400);
DISPLAY 0.617021 (-600 3400);
PAINT AQUA (-600 3400);
DISPLAY INVISIBLE (-600 3400);
FORCEPROP 2 LAST SEC 1
J 0
(-600 3500);
DISPLAY 0.680851 (-600 3500);
PAINT MONO (-600 3500);
DISPLAY INVISIBLE (-600 3500);
FORCEPROP 2 LAST SEC_TYPE 0603V
J 0
(-600 3500);
DISPLAY 1.021277 (-600 3500);
PAINT ORANGE (-600 3500);
DISPLAY INVISIBLE (-600 3500);
FORCEPROP 2 LAST CDS_LIB dev_discrete
J 0
(-650 3300);
PAINT ORANGE (-650 3300);
DISPLAY INVISIBLE (-650 3300);
FORCEADD CAP_A..1
(-500 750);
FORCEPROP 0 LAST GROUP PWR_MLCC_CAP
J 0
(-452 502);
DISPLAY 0.638298 (-452 502);
PAINT BROWN (-452 502);
DISPLAY BOTH (-452 502);
FORCEPROP 1 LAST VOLTAGE 4V
J 0
(-450 800);
DISPLAY 0.617021 (-450 800);
PAINT SKYBLUE (-450 800);
FORCEPROP 1 LAST MATERIAL X6S
J 0
(-450 700);
DISPLAY 0.617021 (-450 700);
PAINT SKYBLUE (-450 700);
FORCEPROP 1 LAST PACK_TYPE 0603V
J 0
(-450 600);
DISPLAY 0.617021 (-450 600);
PAINT SKYBLUE (-450 600);
FORCEPROP 1 LASTPIN (-500 850) $PN 1
J 0
(-490 830);
DISPLAY 0.617021 (-490 830);
PAINT ORANGE (-490 830);
FORCEPROP 1 LAST VALUE 22.0UF
J 0
(-450 850);
DISPLAY 0.617021 (-450 850);
PAINT SKYBLUE (-450 850);
FORCEPROP 1 LAST LOCATION C6P16
J 0
(-450 900);
DISPLAY 0.617021 (-450 900);
PAINT AQUA (-450 900);
FORCEPROP 1 LAST TOLERANCE 20%
J 0
(-450 750);
DISPLAY 0.617021 (-450 750);
PAINT SKYBLUE (-450 750);
FORCEPROP 1 LAST PART_NUMBER E15431-004
J 0
(-450 650);
DISPLAY 0.617021 (-450 650);
PAINT BLUE (-450 650);
FORCEPROP 1 LASTPIN (-500 650) $PN 2
J 0
(-490 630);
DISPLAY 0.617021 (-490 630);
PAINT ORANGE (-490 630);
FORCEPROP 2 LAST SEC_TYPE 0603V
J 0
(-450 950);
DISPLAY 1.021277 (-450 950);
PAINT ORANGE (-450 950);
DISPLAY INVISIBLE (-450 950);
FORCEPROP 2 LAST CDS_SEC 1
J 0
(-450 900);
PAINT ORANGE (-450 900);
DISPLAY INVISIBLE (-450 900);
FORCEPROP 2 LAST CDS_LOCATION C6P16
J 0
(-450 850);
DISPLAY 0.617021 (-450 850);
PAINT AQUA (-450 850);
DISPLAY INVISIBLE (-450 850);
FORCEPROP 1 LAST PATH I62
J 0
(-450 900);
DISPLAY 0.978723 (-450 900);
PAINT WHITE (-450 900);
DISPLAY INVISIBLE (-450 900);
FORCEPROP 2 LAST SEC 1
J 0
(-450 950);
DISPLAY 0.680851 (-450 950);
PAINT MONO (-450 950);
DISPLAY INVISIBLE (-450 950);
FORCEPROP 2 LAST CDS_LIB dev_discrete
J 0
(-500 750);
PAINT ORANGE (-500 750);
DISPLAY INVISIBLE (-500 750);
FORCEADD IR354XX..1
(-3425 3800);
FORCEPROP 1 LAST PART_NUMBER H73688-001
J 0
(-3875 3100);
DISPLAY 0.617021 (-3875 3100);
PAINT BLUE (-3875 3100);
FORCEPROP 2 LASTPIN (-3925 3600) $PN 39
J 2
(-3935 3610);
DISPLAY 0.617021 (-3935 3610);
PAINT MONO (-3935 3610);
FORCEPROP 2 LASTPIN (-3925 3500) $PN 33
J 2
(-3935 3510);
DISPLAY 0.617021 (-3935 3510);
PAINT MONO (-3935 3510);
FORCEPROP 2 LASTPIN (-3925 3700) $PN 34
J 2
(-3935 3710);
DISPLAY 0.617021 (-3935 3710);
PAINT MONO (-3935 3710);
FORCEPROP 2 LASTPIN (-2925 4100) $PN 31
J 0
(-2915 4110);
DISPLAY 0.617021 (-2915 4110);
PAINT MONO (-2915 4110);
FORCEPROP 2 LASTPIN (-3925 4150) $PN 4
J 2
(-3935 4160);
DISPLAY 0.617021 (-3935 4160);
PAINT MONO (-3935 4160);
FORCEPROP 2 LASTPIN (-2925 4150) $PN 37
J 0
(-2915 4160);
DISPLAY 0.617021 (-2915 4160);
PAINT MONO (-2915 4160);
FORCEPROP 2 LASTPIN (-2925 4350) $PN 38
J 0
(-2915 4360);
DISPLAY 0.617021 (-2915 4360);
PAINT MONO (-2915 4360);
FORCEPROP 1 LAST MATERIAL IC
J 0
(-3875 4550);
DISPLAY 0.617021 (-3875 4550);
PAINT SKYBLUE (-3875 4550);
FORCEPROP 2 LASTPIN (-3925 3850) $PN 41
J 2
(-3935 3860);
DISPLAY 0.617021 (-3935 3860);
PAINT MONO (-3935 3860);
FORCEPROP 2 LASTPIN (-3925 3800) $PN 6
J 2
(-3935 3810);
DISPLAY 0.617021 (-3935 3810);
PAINT MONO (-3935 3810);
FORCEPROP 2 LASTPIN (-2925 3500) $PN 10
J 0
(-2915 3510);
DISPLAY 0.617021 (-2915 3510);
PAINT MONO (-2915 3510);
FORCEPROP 2 LASTPIN (-3925 3450) $PN 32
J 2
(-3935 3460);
DISPLAY 0.617021 (-3935 3460);
PAINT MONO (-3935 3460);
FORCEPROP 2 LASTPIN (-3925 4050) $PN 35
J 2
(-3935 4060);
DISPLAY 0.617021 (-3935 4060);
PAINT MONO (-3935 4060);
FORCEPROP 2 LASTPIN (-2925 3250) $PN 5
J 0
(-2915 3260);
DISPLAY 0.617021 (-2915 3260);
PAINT MONO (-2915 3260);
FORCEPROP 2 LASTPIN (-3925 4300) $PN 30
J 2
(-3935 4310);
DISPLAY 0.617021 (-3935 4310);
PAINT MONO (-3935 4310);
FORCEPROP 2 LASTPIN (-3925 4250) $PN 25
J 2
(-3935 4260);
DISPLAY 0.617021 (-3935 4260);
PAINT MONO (-3935 4260);
FORCEPROP 2 LASTPIN (-2925 3400) $PN 2
J 0
(-2915 3410);
DISPLAY 0.617021 (-2915 3410);
PAINT MONO (-2915 3410);
FORCEPROP 2 LASTPIN (-3925 4350) $PN 3
J 2
(-3935 4360);
DISPLAY 0.617021 (-3935 4360);
PAINT MONO (-3935 4360);
FORCEPROP 2 LASTPIN (-3925 3950) $PN 1
J 2
(-3935 3960);
DISPLAY 0.617021 (-3935 3960);
PAINT MONO (-3935 3960);
FORCEPROP 1 LAST LOCATION EU4E1
J 0
(-3875 4600);
DISPLAY 0.617021 (-3875 4600);
PAINT AQUA (-3875 4600);
FORCEPROP 2 LASTPIN (-2925 3850) $PN 36
J 0
(-2915 3860);
DISPLAY 0.617021 (-2915 3860);
PAINT MONO (-2915 3860);
FORCEPROP 2 LASTPIN (-2925 3300) $PN 7
J 0
(-2915 3310);
DISPLAY 0.617021 (-2915 3310);
PAINT MONO (-2915 3310);
FORCEPROP 2 LASTPIN (-2925 3350) $PN 40
J 0
(-2915 3360);
DISPLAY 0.617021 (-2915 3360);
PAINT MONO (-2915 3360);
FORCEPROP 1 LAST VALUE IR35411
J 1
(-3425 4425);
DISPLAY 0.617021 (-3425 4425);
PAINT SKYBLUE (-3425 4425);
DISPLAY INVISIBLE (-3425 4425);
FORCEPROP 1 LAST PATH I63
J 0
(-3425 4550);
PAINT GREEN (-3425 4550);
DISPLAY INVISIBLE (-3425 4550);
FORCEPROP 2 LAST $SEC 1
J 0
(-3875 4650);
PAINT MONO (-3875 4650);
DISPLAY INVISIBLE (-3875 4650);
FORCEPROP 2 LAST CDS_SEC 1
J 0
(-3875 4650);
PAINT MONO (-3875 4650);
DISPLAY INVISIBLE (-3875 4650);
FORCEPROP 1 LAST PACK_TYPE SM
J 0
(-3875 4650);
PAINT SKYBLUE (-3875 4650);
DISPLAY INVISIBLE (-3875 4650);
FORCEPROP 2 LAST CDS_LOCATION EU4E1
J 0
(-3875 4600);
PAINT GREEN (-3875 4600);
DISPLAY INVISIBLE (-3875 4600);
FORCEPROP 2 LAST CDS_LIB mstr_discrete
J 0
(-3425 3800);
PAINT ORANGE (-3425 3800);
DISPLAY INVISIBLE (-3425 3800);
FORCEADD IR354XX..1
(-3475 1175);
FORCEPROP 2 LASTPIN (-3975 975) $PN 39
J 2
(-3985 985);
DISPLAY 0.617021 (-3985 985);
PAINT MONO (-3985 985);
FORCEPROP 2 LASTPIN (-3975 1175) $PN 6
J 2
(-3985 1185);
DISPLAY 0.617021 (-3985 1185);
PAINT MONO (-3985 1185);
FORCEPROP 2 LASTPIN (-2975 625) $PN 5
J 0
(-2965 635);
DISPLAY 0.617021 (-2965 635);
PAINT MONO (-2965 635);
FORCEPROP 2 LASTPIN (-3975 875) $PN 33
J 2
(-3985 885);
DISPLAY 0.617021 (-3985 885);
PAINT MONO (-3985 885);
FORCEPROP 1 LAST PART_NUMBER H73688-001
J 0
(-3850 475);
DISPLAY 0.617021 (-3850 475);
PAINT BLUE (-3850 475);
FORCEPROP 2 LASTPIN (-3975 1075) $PN 34
J 2
(-3985 1085);
DISPLAY 0.617021 (-3985 1085);
PAINT MONO (-3985 1085);
FORCEPROP 2 LASTPIN (-2975 1725) $PN 38
J 0
(-2965 1735);
DISPLAY 0.617021 (-2965 1735);
PAINT MONO (-2965 1735);
FORCEPROP 2 LASTPIN (-2975 1225) $PN 36
J 0
(-2965 1235);
DISPLAY 0.617021 (-2965 1235);
PAINT MONO (-2965 1235);
FORCEPROP 2 LASTPIN (-3975 1675) $PN 30
J 2
(-3985 1685);
DISPLAY 0.617021 (-3985 1685);
PAINT MONO (-3985 1685);
FORCEPROP 1 LAST MATERIAL IC
J 0
(-3925 1925);
DISPLAY 0.617021 (-3925 1925);
PAINT SKYBLUE (-3925 1925);
FORCEPROP 2 LASTPIN (-3975 1525) $PN 4
J 2
(-3985 1535);
DISPLAY 0.617021 (-3985 1535);
PAINT MONO (-3985 1535);
FORCEPROP 2 LASTPIN (-3975 1425) $PN 35
J 2
(-3985 1435);
DISPLAY 0.617021 (-3985 1435);
PAINT MONO (-3985 1435);
FORCEPROP 2 LASTPIN (-3975 1325) $PN 1
J 2
(-3985 1335);
DISPLAY 0.617021 (-3985 1335);
PAINT MONO (-3985 1335);
FORCEPROP 2 LASTPIN (-3975 1225) $PN 41
J 2
(-3985 1235);
DISPLAY 0.617021 (-3985 1235);
PAINT MONO (-3985 1235);
FORCEPROP 2 LASTPIN (-3975 1625) $PN 25
J 2
(-3985 1635);
DISPLAY 0.617021 (-3985 1635);
PAINT MONO (-3985 1635);
FORCEPROP 2 LASTPIN (-2975 1525) $PN 37
J 0
(-2965 1535);
DISPLAY 0.617021 (-2965 1535);
PAINT MONO (-2965 1535);
FORCEPROP 2 LASTPIN (-2975 875) $PN 10
J 0
(-2965 885);
DISPLAY 0.617021 (-2965 885);
PAINT MONO (-2965 885);
FORCEPROP 2 LASTPIN (-3975 1725) $PN 3
J 2
(-3985 1735);
DISPLAY 0.617021 (-3985 1735);
PAINT MONO (-3985 1735);
FORCEPROP 1 LAST LOCATION EU4D6
J 0
(-3925 1975);
DISPLAY 0.617021 (-3925 1975);
PAINT AQUA (-3925 1975);
FORCEPROP 2 LASTPIN (-2975 1475) $PN 31
J 0
(-2965 1485);
DISPLAY 0.617021 (-2965 1485);
PAINT MONO (-2965 1485);
FORCEPROP 2 LASTPIN (-2975 675) $PN 7
J 0
(-2965 685);
DISPLAY 0.617021 (-2965 685);
PAINT MONO (-2965 685);
FORCEPROP 2 LASTPIN (-2975 725) $PN 40
J 0
(-2965 735);
DISPLAY 0.617021 (-2965 735);
PAINT MONO (-2965 735);
FORCEPROP 2 LASTPIN (-3975 825) $PN 32
J 2
(-3985 835);
DISPLAY 0.617021 (-3985 835);
PAINT MONO (-3985 835);
FORCEPROP 2 LASTPIN (-2975 775) $PN 2
J 0
(-2965 785);
DISPLAY 0.617021 (-2965 785);
PAINT MONO (-2965 785);
FORCEPROP 1 LAST VALUE IR35411
J 1
(-3475 1800);
DISPLAY 0.617021 (-3475 1800);
PAINT SKYBLUE (-3475 1800);
DISPLAY INVISIBLE (-3475 1800);
FORCEPROP 1 LAST PACK_TYPE SM
J 0
(-3925 2025);
PAINT SKYBLUE (-3925 2025);
DISPLAY INVISIBLE (-3925 2025);
FORCEPROP 2 LAST CDS_SEC 1
J 0
(-3925 2025);
PAINT MONO (-3925 2025);
DISPLAY INVISIBLE (-3925 2025);
FORCEPROP 2 LAST $SEC 1
J 0
(-3925 2025);
PAINT MONO (-3925 2025);
DISPLAY INVISIBLE (-3925 2025);
FORCEPROP 2 LAST CDS_LIB mstr_discrete
J 0
(-3475 1175);
PAINT ORANGE (-3475 1175);
DISPLAY INVISIBLE (-3475 1175);
FORCEPROP 1 LAST PATH I64
J 0
(-3475 1925);
PAINT GREEN (-3475 1925);
DISPLAY INVISIBLE (-3475 1925);
FORCEPROP 2 LAST CDS_LOCATION EU4D6
J 0
(-3925 1975);
PAINT GREEN (-3925 1975);
DISPLAY INVISIBLE (-3925 1975);
FORCEADD RES..2
(-750 3900);
FORCEPROP 1 LAST PART_NUMBER G21796-187
J 0
(-710 3775);
DISPLAY 0.617021 (-710 3775);
PAINT BLUE (-710 3775);
FORCEPROP 1 LAST PACK_TYPE 0402
J 0
(-710 3725);
DISPLAY 0.617021 (-710 3725);
PAINT SKYBLUE (-710 3725);
FORCEPROP 1 LAST MATERIAL EMPTY
J 0
(-710 3825);
DISPLAY 0.617021 (-710 3825);
PAINT RED (-710 3825);
FORCEPROP 1 LASTPIN (-750 3800) $PN 2
J 0
(-745 3810);
DISPLAY 0.787234 (-745 3810);
PAINT ORANGE (-745 3810);
FORCEPROP 1 LASTPIN (-750 4000) $PN 1
J 0
(-745 3962);
DISPLAY 0.787234 (-745 3962);
PAINT ORANGE (-745 3962);
FORCEPROP 1 LAST LOCATION R4E22
J 0
(-705 4025);
DISPLAY 0.617021 (-705 4025);
PAINT AQUA (-705 4025);
FORCEPROP 1 LAST TOLERANCE 1%
J 0
(-705 3925);
DISPLAY 0.617021 (-705 3925);
PAINT SKYBLUE (-705 3925);
FORCEPROP 1 LAST VALUE 68.1K
J 0
(-705 3975);
DISPLAY 0.617021 (-705 3975);
PAINT SKYBLUE (-705 3975);
FORCEPROP 1 LAST WATTAGE 1/16W
J 0
(-710 3875);
DISPLAY 0.617021 (-710 3875);
PAINT SKYBLUE (-710 3875);
FORCEPROP 2 LAST SEC_TYPE 0402
J 0
(-700 4125);
DISPLAY 1.021277 (-700 4125);
PAINT ORANGE (-700 4125);
DISPLAY INVISIBLE (-700 4125);
FORCEPROP 2 LAST SEC 1
J 0
(-700 4125);
PAINT MONO (-700 4125);
DISPLAY INVISIBLE (-700 4125);
FORCEPROP 2 LAST CDS_LIB mstr_discrete
J 0
(-750 3900);
PAINT ORANGE (-750 3900);
DISPLAY INVISIBLE (-750 3900);
FORCEPROP 1 LAST PATH I65
J 0
(-700 4075);
DISPLAY 0.978723 (-700 4075);
PAINT WHITE (-700 4075);
DISPLAY INVISIBLE (-700 4075);
FORCEADD GND..1
(-750 3700);
FORCEPROP 3 LASTPIN (-750 3750) SIG_NAME GND\g
J 0
(-740 3760);
DISPLAY 0.659574 (-740 3760);
PAINT MONO (-740 3760);
DISPLAY INVISIBLE (-740 3760);
FORCEPROP 2 LAST ROOM PVCCIN_CPU0_PWR_VR
J 0
(-1300 3775);
DISPLAY 1.936170 (-1300 3775);
PAINT ORANGE (-1300 3775);
DISPLAY INVISIBLE (-1300 3775);
FORCEPROP 2 LAST BOM_COST PROC_VRD_VCCIN_CPU0
J 0
(-1125 3775);
DISPLAY 1.446809 (-1125 3775);
PAINT MONO (-1125 3775);
DISPLAY INVISIBLE (-1125 3775);
FORCEPROP 1 LAST PATH I66
J 0
(-675 3700);
DISPLAY 0.872340 (-675 3700);
PAINT AQUA (-675 3700);
DISPLAY INVISIBLE (-675 3700);
FORCEPROP 1 LAST SIZE 1B
J 0
(-675 3650);
DISPLAY 1.723404 (-675 3650);
PAINT GREEN (-675 3650);
DISPLAY INVISIBLE (-675 3650);
FORCEPROP 2 LAST CDS_LIB mstr_symbols
J 0
(-750 3700);
PAINT ORANGE (-750 3700);
DISPLAY INVISIBLE (-750 3700);
FORCEPROP 1 LAST VOLTAGE 0
J 0
(-750 3700);
PAINT SKYBLUE (-750 3700);
DISPLAY INVISIBLE (-750 3700);
FORCEPROP 1 LAST BODY_TYPE PLUMBING
J 0
(-795 3657);
DISPLAY 0.340426 (-795 3657);
PAINT GREEN (-795 3657);
DISPLAY INVISIBLE (-795 3657);
FORCEPROP 1 LAST HDL_POWER GND
J 0
(-750 3850);
DISPLAY 1.723404 (-750 3850);
PAINT GREEN (-750 3850);
DISPLAY INVISIBLE (-750 3850);
FORCEADD RES..2
(-825 1350);
FORCEPROP 1 LAST PART_NUMBER G21796-187
J 0
(-785 1225);
DISPLAY 0.617021 (-785 1225);
PAINT BLUE (-785 1225);
FORCEPROP 1 LAST VALUE 68.1K
J 0
(-780 1425);
DISPLAY 0.617021 (-780 1425);
PAINT SKYBLUE (-780 1425);
FORCEPROP 1 LAST PACK_TYPE 0402
J 0
(-785 1175);
DISPLAY 0.617021 (-785 1175);
PAINT SKYBLUE (-785 1175);
FORCEPROP 1 LAST LOCATION R4E19
J 0
(-780 1475);
DISPLAY 0.617021 (-780 1475);
PAINT AQUA (-780 1475);
FORCEPROP 1 LAST TOLERANCE 1%
J 0
(-780 1375);
DISPLAY 0.617021 (-780 1375);
PAINT SKYBLUE (-780 1375);
FORCEPROP 1 LAST MATERIAL EMPTY
J 0
(-785 1275);
DISPLAY 0.617021 (-785 1275);
PAINT RED (-785 1275);
FORCEPROP 1 LAST WATTAGE 1/16W
J 0
(-785 1325);
DISPLAY 0.617021 (-785 1325);
PAINT SKYBLUE (-785 1325);
FORCEPROP 1 LASTPIN (-825 1250) $PN 2
J 0
(-820 1260);
DISPLAY 0.787234 (-820 1260);
PAINT ORANGE (-820 1260);
DISPLAY INVISIBLE (-820 1260);
FORCEPROP 2 LAST CDS_LIB mstr_discrete
J 0
(-825 1350);
PAINT ORANGE (-825 1350);
DISPLAY INVISIBLE (-825 1350);
FORCEPROP 1 LASTPIN (-825 1450) $PN 1
J 0
(-820 1412);
DISPLAY 0.787234 (-820 1412);
PAINT ORANGE (-820 1412);
DISPLAY INVISIBLE (-820 1412);
FORCEPROP 1 LAST PATH I67
J 0
(-775 1525);
DISPLAY 0.978723 (-775 1525);
PAINT WHITE (-775 1525);
DISPLAY INVISIBLE (-775 1525);
FORCEPROP 2 LAST $SEC 1
J 0
(-775 1575);
PAINT MONO (-775 1575);
DISPLAY INVISIBLE (-775 1575);
FORCEPROP 2 LAST CDS_SEC 1
J 0
(-775 1575);
PAINT MONO (-775 1575);
DISPLAY INVISIBLE (-775 1575);
FORCEADD GND..1
(-825 1150);
FORCEPROP 3 LASTPIN (-825 1200) SIG_NAME GND\g
J 0
(-815 1210);
DISPLAY 0.659574 (-815 1210);
PAINT MONO (-815 1210);
DISPLAY INVISIBLE (-815 1210);
FORCEPROP 2 LAST ROOM PVCCIN_CPU0_PWR_VR
J 0
(-1375 1225);
DISPLAY 1.936170 (-1375 1225);
PAINT ORANGE (-1375 1225);
DISPLAY INVISIBLE (-1375 1225);
FORCEPROP 2 LAST BOM_COST PROC_VRD_VCCIN_CPU0
J 0
(-1200 1225);
DISPLAY 1.446809 (-1200 1225);
PAINT MONO (-1200 1225);
DISPLAY INVISIBLE (-1200 1225);
FORCEPROP 2 LAST CDS_LIB mstr_symbols
J 0
(-825 1150);
PAINT ORANGE (-825 1150);
DISPLAY INVISIBLE (-825 1150);
FORCEPROP 1 LAST VOLTAGE 0
J 0
(-825 1150);
PAINT SKYBLUE (-825 1150);
DISPLAY INVISIBLE (-825 1150);
FORCEPROP 1 LAST PATH I68
J 0
(-750 1150);
DISPLAY 0.872340 (-750 1150);
PAINT AQUA (-750 1150);
DISPLAY INVISIBLE (-750 1150);
FORCEPROP 1 LAST SIZE 1B
J 0
(-750 1100);
DISPLAY 1.723404 (-750 1100);
PAINT GREEN (-750 1100);
DISPLAY INVISIBLE (-750 1100);
FORCEPROP 1 LAST BODY_TYPE PLUMBING
J 0
(-870 1107);
DISPLAY 0.340426 (-870 1107);
PAINT GREEN (-870 1107);
DISPLAY INVISIBLE (-870 1107);
FORCEPROP 1 LAST HDL_POWER GND
J 0
(-825 1300);
DISPLAY 1.723404 (-825 1300);
PAINT GREEN (-825 1300);
DISPLAY INVISIBLE (-825 1300);
FORCEADD CAP_A..1
(-4125 3300);
FORCEPROP 1 LAST PART_NUMBER A36096-030
J 0
(-4075 3150);
DISPLAY 0.617021 (-4075 3150);
PAINT BLUE (-4075 3150);
FORCEPROP 1 LAST PACK_TYPE 0402V
J 0
(-4075 3100);
DISPLAY 0.617021 (-4075 3100);
PAINT SKYBLUE (-4075 3100);
FORCEPROP 0 LAST POP NOPOP
J 0
(-4025 3050);
DISPLAY 0.638298 (-4025 3050);
PAINT RED (-4025 3050);
FORCEPROP 1 LAST VALUE 0.1UF
J 0
(-4075 3350);
DISPLAY 0.617021 (-4075 3350);
PAINT SKYBLUE (-4075 3350);
FORCEPROP 1 LAST LOCATION CT1
J 0
(-4275 3300);
DISPLAY 0.617021 (-4275 3300);
PAINT AQUA (-4275 3300);
FORCEPROP 1 LAST MATERIAL X7R
J 0
(-4075 3200);
DISPLAY 0.617021 (-4075 3200);
PAINT SKYBLUE (-4075 3200);
FORCEPROP 1 LASTPIN (-4125 3200) $PN 2
J 0
(-4115 3180);
DISPLAY 0.787234 (-4115 3180);
PAINT ORANGE (-4115 3180);
FORCEPROP 1 LAST TOLERANCE 10%
J 0
(-4075 3250);
DISPLAY 0.617021 (-4075 3250);
PAINT SKYBLUE (-4075 3250);
FORCEPROP 1 LAST VOLTAGE 16V
J 0
(-4075 3300);
DISPLAY 0.617021 (-4075 3300);
PAINT SKYBLUE (-4075 3300);
FORCEPROP 1 LASTPIN (-4125 3400) $PN 1
J 0
(-4115 3380);
DISPLAY 0.787234 (-4115 3380);
PAINT ORANGE (-4115 3380);
FORCEPROP 2 LAST CDS_LIB dev_discrete
J 0
(-4125 3300);
PAINT MONO (-4125 3300);
DISPLAY INVISIBLE (-4125 3300);
FORCEPROP 1 LAST PATH I70
J 0
(-4075 3450);
DISPLAY 0.978723 (-4075 3450);
PAINT WHITE (-4075 3450);
DISPLAY INVISIBLE (-4075 3450);
FORCEPROP 2 LAST ROOM PVCCIN_CPU0_PWR_VR
J 0
(-4075 3450);
DISPLAY 1.361702 (-4075 3450);
PAINT ORANGE (-4075 3450);
DISPLAY INVISIBLE (-4075 3450);
FORCEPROP 0 LAST SEC 1
J 0
(-4075 3400);
DISPLAY 0.680851 (-4075 3400);
PAINT MONO (-4075 3400);
DISPLAY INVISIBLE (-4075 3400);
FORCEPROP 2 LAST SEC_TYPE 0402V
J 0
(-4075 3500);
DISPLAY 1.021277 (-4075 3500);
PAINT ORANGE (-4075 3500);
DISPLAY INVISIBLE (-4075 3500);
FORCEADD GND..1
(-4125 3050);
FORCEPROP 3 LASTPIN (-4125 3100) SIG_NAME GND\g
J 0
(-4115 3110);
DISPLAY 0.659574 (-4115 3110);
PAINT MONO (-4115 3110);
DISPLAY INVISIBLE (-4115 3110);
FORCEPROP 2 LAST CDS_LIB mstr_symbols
J 0
(-4125 3050);
PAINT MONO (-4125 3050);
DISPLAY INVISIBLE (-4125 3050);
FORCEPROP 1 LAST PATH I71
J 0
(-4050 3050);
DISPLAY 0.872340 (-4050 3050);
PAINT AQUA (-4050 3050);
DISPLAY INVISIBLE (-4050 3050);
FORCEPROP 1 LAST VOLTAGE 0
J 0
(-4125 3050);
PAINT SKYBLUE (-4125 3050);
DISPLAY INVISIBLE (-4125 3050);
FORCEPROP 1 LAST SIZE 1B
J 0
(-4050 3000);
DISPLAY 1.723404 (-4050 3000);
PAINT GREEN (-4050 3000);
DISPLAY INVISIBLE (-4050 3000);
FORCEPROP 2 LAST BOM_COST PROC_VRD_VCCIN_CPU0
J 0
(-4500 3125);
DISPLAY 1.446809 (-4500 3125);
PAINT MONO (-4500 3125);
DISPLAY INVISIBLE (-4500 3125);
FORCEPROP 2 LAST ROOM PVCCIN_CPU0_PWR_VR
J 0
(-4675 3125);
DISPLAY 1.936170 (-4675 3125);
PAINT ORANGE (-4675 3125);
DISPLAY INVISIBLE (-4675 3125);
FORCEPROP 1 LAST BODY_TYPE PLUMBING
J 0
(-4170 3007);
DISPLAY 0.340426 (-4170 3007);
PAINT GREEN (-4170 3007);
DISPLAY INVISIBLE (-4170 3007);
FORCEPROP 1 LAST HDL_POWER GND
J 0
(-4125 3200);
DISPLAY 1.723404 (-4125 3200);
PAINT GREEN (-4125 3200);
DISPLAY INVISIBLE (-4125 3200);
FORCEADD GND..1
(-2350 3625);
FORCEPROP 3 LASTPIN (-2350 3675) SIG_NAME GND\g
J 0
(-2340 3685);
DISPLAY 0.659574 (-2340 3685);
PAINT MONO (-2340 3685);
DISPLAY INVISIBLE (-2340 3685);
FORCEPROP 2 LAST CDS_LIB mstr_symbols
J 0
(-2350 3625);
PAINT MONO (-2350 3625);
DISPLAY INVISIBLE (-2350 3625);
FORCEPROP 1 LAST PATH I73
J 0
(-2275 3625);
DISPLAY 0.872340 (-2275 3625);
PAINT AQUA (-2275 3625);
DISPLAY INVISIBLE (-2275 3625);
FORCEPROP 2 LAST ROOM VDDQ_KLM_PWR_VR
J 0
(-2925 3700);
DISPLAY 1.361702 (-2925 3700);
PAINT ORANGE (-2925 3700);
DISPLAY INVISIBLE (-2925 3700);
FORCEPROP 1 LAST VOLTAGE 0
J 0
(-2350 3625);
PAINT SKYBLUE (-2350 3625);
DISPLAY INVISIBLE (-2350 3625);
FORCEPROP 1 LAST SIZE 1B
J 0
(-2275 3575);
DISPLAY 1.170213 (-2275 3575);
PAINT AQUA (-2275 3575);
DISPLAY INVISIBLE (-2275 3575);
FORCEPROP 1 LAST BODY_TYPE PLUMBING
J 0
(-2395 3582);
DISPLAY 0.340426 (-2395 3582);
PAINT GREEN (-2395 3582);
DISPLAY INVISIBLE (-2395 3582);
FORCEPROP 1 LAST HDL_POWER GND
J 0
(-2350 3775);
DISPLAY 1.170213 (-2350 3775);
PAINT GREEN (-2350 3775);
DISPLAY INVISIBLE (-2350 3775);
FORCEADD GND..1
(-2550 2750);
FORCEPROP 3 LASTPIN (-2550 2800) SIG_NAME GND\g
J 0
(-2540 2810);
DISPLAY 0.659574 (-2540 2810);
PAINT MONO (-2540 2810);
DISPLAY INVISIBLE (-2540 2810);
FORCEPROP 2 LAST CDS_LIB mstr_symbols
J 0
(-2550 2750);
PAINT MONO (-2550 2750);
DISPLAY INVISIBLE (-2550 2750);
FORCEPROP 1 LAST PATH I77
J 0
(-2475 2750);
DISPLAY 0.872340 (-2475 2750);
PAINT AQUA (-2475 2750);
DISPLAY INVISIBLE (-2475 2750);
FORCEPROP 2 LAST ROOM PVCCIN_CPU0_PWR_VR
J 0
(-3100 2825);
DISPLAY 1.936170 (-3100 2825);
PAINT ORANGE (-3100 2825);
DISPLAY INVISIBLE (-3100 2825);
FORCEPROP 2 LAST BOM_COST PROC_VRD_VCCIN_CPU0
J 0
(-2925 2825);
DISPLAY 1.446809 (-2925 2825);
PAINT MONO (-2925 2825);
DISPLAY INVISIBLE (-2925 2825);
FORCEPROP 1 LAST VOLTAGE 0
J 0
(-2550 2750);
PAINT SKYBLUE (-2550 2750);
DISPLAY INVISIBLE (-2550 2750);
FORCEPROP 1 LAST SIZE 1B
J 0
(-2475 2700);
DISPLAY 1.723404 (-2475 2700);
PAINT GREEN (-2475 2700);
DISPLAY INVISIBLE (-2475 2700);
FORCEPROP 1 LAST BODY_TYPE PLUMBING
J 0
(-2595 2707);
DISPLAY 0.340426 (-2595 2707);
PAINT GREEN (-2595 2707);
DISPLAY INVISIBLE (-2595 2707);
FORCEPROP 1 LAST HDL_POWER GND
J 0
(-2550 2900);
DISPLAY 1.723404 (-2550 2900);
PAINT GREEN (-2550 2900);
DISPLAY INVISIBLE (-2550 2900);
FORCEADD CAP..1
(-2350 3875);
FORCEPROP 0 LAST POP NOPOP
J 0
(-2675 3850);
DISPLAY 1.021277 (-2675 3850);
PAINT RED (-2675 3850);
FORCEPROP 1 LASTPIN (-2350 3775) $PN 2
J 0
(-2340 3755);
DISPLAY 0.617021 (-2340 3755);
PAINT ORANGE (-2340 3755);
FORCEPROP 1 LASTPIN (-2350 3975) $PN 1
J 0
(-2340 3955);
DISPLAY 0.617021 (-2340 3955);
PAINT ORANGE (-2340 3955);
FORCEPROP 1 LAST LOCATION CT2
J 0
(-2300 3975);
DISPLAY 0.617021 (-2300 3975);
PAINT AQUA (-2300 3975);
FORCEPROP 1 LAST VALUE 1000PF
J 0
(-2300 3925);
DISPLAY 0.617021 (-2300 3925);
PAINT SKYBLUE (-2300 3925);
FORCEPROP 1 LAST VOLTAGE 50V
J 0
(-2300 3875);
DISPLAY 0.617021 (-2300 3875);
PAINT SKYBLUE (-2300 3875);
FORCEPROP 1 LAST TOLERANCE 10%
J 0
(-2300 3825);
DISPLAY 0.617021 (-2300 3825);
PAINT SKYBLUE (-2300 3825);
FORCEPROP 1 LAST MATERIAL X7R
J 0
(-2300 3775);
DISPLAY 0.617021 (-2300 3775);
PAINT SKYBLUE (-2300 3775);
FORCEPROP 1 LAST PART_NUMBER A36096-046
J 0
(-2300 3725);
DISPLAY 0.617021 (-2300 3725);
PAINT BLUE (-2300 3725);
FORCEPROP 1 LAST PACK_TYPE 0402LF
J 0
(-2300 3675);
DISPLAY 0.617021 (-2300 3675);
PAINT SKYBLUE (-2300 3675);
FORCEPROP 2 LAST CDS_LIB mstr_discrete
J 0
(-2350 3875);
PAINT MONO (-2350 3875);
DISPLAY INVISIBLE (-2350 3875);
FORCEPROP 2 LAST CDS_LOCATION CT2
J 0
(-2300 3975);
DISPLAY 0.617021 (-2300 3975);
PAINT AQUA (-2300 3975);
DISPLAY INVISIBLE (-2300 3975);
FORCEPROP 2 LAST SEC 1
J 0
(-2300 4075);
DISPLAY 0.680851 (-2300 4075);
PAINT MONO (-2300 4075);
DISPLAY INVISIBLE (-2300 4075);
FORCEPROP 2 LAST SEC_TYPE 0402LF
J 0
(-2300 4075);
DISPLAY 1.021277 (-2300 4075);
PAINT ORANGE (-2300 4075);
DISPLAY INVISIBLE (-2300 4075);
FORCEPROP 1 LAST PATH I78
J 0
(-2300 4025);
DISPLAY 0.978723 (-2300 4025);
PAINT WHITE (-2300 4025);
DISPLAY INVISIBLE (-2300 4025);
FORCEPROP 0 LAST ROOM VDDQ_KLM_PWR_VR
J 0
(-2300 4075);
DISPLAY 1.021277 (-2300 4075);
PAINT ORANGE (-2300 4075);
DISPLAY INVISIBLE (-2300 4075);
FORCEADD GND..1
(-650 3025);
FORCEPROP 3 LASTPIN (-650 3075) SIG_NAME GND\g
J 0
(-640 3085);
DISPLAY 0.659574 (-640 3085);
PAINT MONO (-640 3085);
DISPLAY INVISIBLE (-640 3085);
FORCEPROP 2 LAST CDS_LIB mstr_symbols
J 0
(-650 3025);
DISPLAY 1.936170 (-650 3025);
PAINT ORANGE (-650 3025);
DISPLAY INVISIBLE (-650 3025);
FORCEPROP 1 LAST PATH I8
J 0
(-575 3025);
DISPLAY 0.872340 (-575 3025);
PAINT AQUA (-575 3025);
DISPLAY INVISIBLE (-575 3025);
FORCEPROP 1 LAST VOLTAGE 0
J 0
(-650 3025);
PAINT SKYBLUE (-650 3025);
DISPLAY INVISIBLE (-650 3025);
FORCEPROP 1 LAST SIZE 1B
J 0
(-575 2975);
DISPLAY 1.723404 (-575 2975);
PAINT GREEN (-575 2975);
DISPLAY INVISIBLE (-575 2975);
FORCEPROP 2 LAST BOM_COST PROC_VRD_VCCIN_CPU0
J 0
(-1025 3100);
DISPLAY 1.446809 (-1025 3100);
PAINT MONO (-1025 3100);
DISPLAY INVISIBLE (-1025 3100);
FORCEPROP 2 LAST ROOM PVCCIN_CPU0_PWR_VR
J 0
(-1200 3100);
DISPLAY 1.936170 (-1200 3100);
PAINT ORANGE (-1200 3100);
DISPLAY INVISIBLE (-1200 3100);
FORCEPROP 1 LAST BODY_TYPE PLUMBING
J 0
(-695 2982);
DISPLAY 0.340426 (-695 2982);
PAINT GREEN (-695 2982);
DISPLAY INVISIBLE (-695 2982);
FORCEPROP 1 LAST HDL_POWER GND
J 0
(-650 3175);
DISPLAY 1.723404 (-650 3175);
PAINT GREEN (-650 3175);
DISPLAY INVISIBLE (-650 3175);
FORCEADD GND..1
(-4175 425);
FORCEPROP 3 LASTPIN (-4175 475) SIG_NAME GND\g
J 0
(-4165 485);
DISPLAY 0.659574 (-4165 485);
PAINT MONO (-4165 485);
DISPLAY INVISIBLE (-4165 485);
FORCEPROP 2 LAST CDS_LIB mstr_symbols
J 0
(-4175 425);
PAINT MONO (-4175 425);
DISPLAY INVISIBLE (-4175 425);
FORCEPROP 1 LAST PATH I80
J 0
(-4100 425);
DISPLAY 0.872340 (-4100 425);
PAINT AQUA (-4100 425);
DISPLAY INVISIBLE (-4100 425);
FORCEPROP 1 LAST VOLTAGE 0
J 0
(-4175 425);
PAINT SKYBLUE (-4175 425);
DISPLAY INVISIBLE (-4175 425);
FORCEPROP 1 LAST SIZE 1B
J 0
(-4100 375);
DISPLAY 1.723404 (-4100 375);
PAINT GREEN (-4100 375);
DISPLAY INVISIBLE (-4100 375);
FORCEPROP 2 LAST BOM_COST PROC_VRD_VCCIN_CPU0
J 0
(-4550 500);
DISPLAY 1.446809 (-4550 500);
PAINT MONO (-4550 500);
DISPLAY INVISIBLE (-4550 500);
FORCEPROP 2 LAST ROOM PVCCIN_CPU0_PWR_VR
J 0
(-4725 500);
DISPLAY 1.936170 (-4725 500);
PAINT ORANGE (-4725 500);
DISPLAY INVISIBLE (-4725 500);
FORCEPROP 1 LAST BODY_TYPE PLUMBING
J 0
(-4220 382);
DISPLAY 0.340426 (-4220 382);
PAINT GREEN (-4220 382);
DISPLAY INVISIBLE (-4220 382);
FORCEPROP 1 LAST HDL_POWER GND
J 0
(-4175 575);
DISPLAY 1.723404 (-4175 575);
PAINT GREEN (-4175 575);
DISPLAY INVISIBLE (-4175 575);
FORCEADD CAP_A..1
(-4175 675);
FORCEPROP 1 LAST PART_NUMBER A36096-030
J 0
(-4125 525);
DISPLAY 0.617021 (-4125 525);
PAINT BLUE (-4125 525);
FORCEPROP 1 LAST LOCATION CT6
J 0
(-4125 775);
DISPLAY 0.617021 (-4125 775);
PAINT AQUA (-4125 775);
FORCEPROP 1 LAST VALUE 0.1UF
J 0
(-4125 725);
DISPLAY 0.617021 (-4125 725);
PAINT SKYBLUE (-4125 725);
FORCEPROP 1 LASTPIN (-4175 575) $PN 2
J 0
(-4165 555);
DISPLAY 0.787234 (-4165 555);
PAINT ORANGE (-4165 555);
FORCEPROP 1 LAST TOLERANCE 10%
J 0
(-4125 625);
DISPLAY 0.617021 (-4125 625);
PAINT SKYBLUE (-4125 625);
FORCEPROP 1 LAST MATERIAL X7R
J 0
(-4125 575);
DISPLAY 0.617021 (-4125 575);
PAINT SKYBLUE (-4125 575);
FORCEPROP 0 LAST POP NOPOP
J 0
(-4125 400);
DISPLAY 0.808511 (-4125 400);
PAINT RED (-4125 400);
FORCEPROP 1 LAST VOLTAGE 16V
J 0
(-4125 675);
DISPLAY 0.617021 (-4125 675);
PAINT SKYBLUE (-4125 675);
FORCEPROP 1 LAST PACK_TYPE 0402V
J 0
(-4125 475);
DISPLAY 0.617021 (-4125 475);
PAINT SKYBLUE (-4125 475);
FORCEPROP 1 LASTPIN (-4175 775) $PN 1
J 0
(-4165 755);
DISPLAY 0.787234 (-4165 755);
PAINT ORANGE (-4165 755);
FORCEPROP 2 LAST SEC_TYPE 0402V
J 0
(-4125 875);
DISPLAY 1.021277 (-4125 875);
PAINT ORANGE (-4125 875);
DISPLAY INVISIBLE (-4125 875);
FORCEPROP 0 LAST SEC 1
J 0
(-4125 800);
DISPLAY 0.680851 (-4125 800);
PAINT MONO (-4125 800);
DISPLAY INVISIBLE (-4125 800);
FORCEPROP 2 LAST CDS_LIB dev_discrete
J 0
(-4175 675);
PAINT MONO (-4175 675);
DISPLAY INVISIBLE (-4175 675);
FORCEPROP 1 LAST PATH I81
J 0
(-4125 825);
DISPLAY 0.978723 (-4125 825);
PAINT WHITE (-4125 825);
DISPLAY INVISIBLE (-4125 825);
FORCEPROP 2 LAST ROOM PVCCIN_CPU0_PWR_VR
J 0
(-4125 825);
DISPLAY 1.361702 (-4125 825);
PAINT ORANGE (-4125 825);
DISPLAY INVISIBLE (-4125 825);
FORCEADD GND..1
(-2550 350);
FORCEPROP 3 LASTPIN (-2550 400) SIG_NAME GND\g
J 0
(-2540 410);
DISPLAY 0.659574 (-2540 410);
PAINT MONO (-2540 410);
DISPLAY INVISIBLE (-2540 410);
FORCEPROP 2 LAST CDS_LIB mstr_symbols
J 0
(-2550 350);
PAINT MONO (-2550 350);
DISPLAY INVISIBLE (-2550 350);
FORCEPROP 1 LAST PATH I84
J 0
(-2475 350);
DISPLAY 0.872340 (-2475 350);
PAINT AQUA (-2475 350);
DISPLAY INVISIBLE (-2475 350);
FORCEPROP 1 LAST SIZE 1B
J 0
(-2475 300);
DISPLAY 1.723404 (-2475 300);
PAINT GREEN (-2475 300);
DISPLAY INVISIBLE (-2475 300);
FORCEPROP 1 LAST VOLTAGE 0
J 0
(-2550 350);
PAINT SKYBLUE (-2550 350);
DISPLAY INVISIBLE (-2550 350);
FORCEPROP 2 LAST BOM_COST PROC_VRD_VCCIN_CPU0
J 0
(-2925 425);
DISPLAY 1.446809 (-2925 425);
PAINT MONO (-2925 425);
DISPLAY INVISIBLE (-2925 425);
FORCEPROP 2 LAST ROOM PVCCIN_CPU0_PWR_VR
J 0
(-3100 425);
DISPLAY 1.936170 (-3100 425);
PAINT ORANGE (-3100 425);
DISPLAY INVISIBLE (-3100 425);
FORCEPROP 1 LAST BODY_TYPE PLUMBING
J 0
(-2595 307);
DISPLAY 0.340426 (-2595 307);
PAINT GREEN (-2595 307);
DISPLAY INVISIBLE (-2595 307);
FORCEPROP 1 LAST HDL_POWER GND
J 0
(-2550 500);
DISPLAY 1.723404 (-2550 500);
PAINT GREEN (-2550 500);
DISPLAY INVISIBLE (-2550 500);
FORCEADD GND..1
(-2450 1050);
FORCEPROP 3 LASTPIN (-2450 1100) SIG_NAME GND\g
J 0
(-2440 1110);
DISPLAY 0.659574 (-2440 1110);
PAINT MONO (-2440 1110);
DISPLAY INVISIBLE (-2440 1110);
FORCEPROP 2 LAST CDS_LIB mstr_symbols
J 0
(-2450 1050);
PAINT MONO (-2450 1050);
DISPLAY INVISIBLE (-2450 1050);
FORCEPROP 1 LAST PATH I86
J 0
(-2375 1050);
DISPLAY 0.872340 (-2375 1050);
PAINT AQUA (-2375 1050);
DISPLAY INVISIBLE (-2375 1050);
FORCEPROP 2 LAST ROOM VDDQ_KLM_PWR_VR
J 0
(-3025 1125);
DISPLAY 1.361702 (-3025 1125);
PAINT ORANGE (-3025 1125);
DISPLAY INVISIBLE (-3025 1125);
FORCEPROP 1 LAST VOLTAGE 0
J 0
(-2450 1050);
PAINT SKYBLUE (-2450 1050);
DISPLAY INVISIBLE (-2450 1050);
FORCEPROP 1 LAST SIZE 1B
J 0
(-2375 1000);
DISPLAY 1.170213 (-2375 1000);
PAINT AQUA (-2375 1000);
DISPLAY INVISIBLE (-2375 1000);
FORCEPROP 1 LAST BODY_TYPE PLUMBING
J 0
(-2495 1007);
DISPLAY 0.340426 (-2495 1007);
PAINT GREEN (-2495 1007);
DISPLAY INVISIBLE (-2495 1007);
FORCEPROP 1 LAST HDL_POWER GND
J 0
(-2450 1200);
DISPLAY 1.170213 (-2450 1200);
PAINT GREEN (-2450 1200);
DISPLAY INVISIBLE (-2450 1200);
FORCEADD CAP..1
(-2450 1250);
FORCEPROP 1 LASTPIN (-2450 1350) $PN 1
J 0
(-2440 1330);
DISPLAY 0.787234 (-2440 1330);
PAINT ORANGE (-2440 1330);
FORCEPROP 1 LAST LOCATION CT4
J 0
(-2600 1250);
DISPLAY 0.617021 (-2600 1250);
PAINT AQUA (-2600 1250);
FORCEPROP 1 LASTPIN (-2450 1150) $PN 2
J 0
(-2440 1130);
DISPLAY 0.787234 (-2440 1130);
PAINT ORANGE (-2440 1130);
FORCEPROP 1 LAST VOLTAGE 50V
J 0
(-2400 1250);
DISPLAY 0.617021 (-2400 1250);
PAINT SKYBLUE (-2400 1250);
FORCEPROP 1 LAST TOLERANCE 10%
J 0
(-2400 1200);
DISPLAY 0.617021 (-2400 1200);
PAINT SKYBLUE (-2400 1200);
FORCEPROP 1 LAST MATERIAL X7R
J 0
(-2400 1150);
DISPLAY 0.617021 (-2400 1150);
PAINT SKYBLUE (-2400 1150);
FORCEPROP 1 LAST VALUE 1000PF
J 0
(-2400 1300);
DISPLAY 0.617021 (-2400 1300);
PAINT SKYBLUE (-2400 1300);
FORCEPROP 1 LAST PACK_TYPE 0402LF
J 0
(-2400 1050);
DISPLAY 0.617021 (-2400 1050);
PAINT SKYBLUE (-2400 1050);
FORCEPROP 0 LAST POP NOPOP
J 0
(-2300 1200);
DISPLAY 1.021277 (-2300 1200);
PAINT RED (-2300 1200);
FORCEPROP 1 LAST PART_NUMBER A36096-046
J 0
(-2400 1100);
DISPLAY 0.617021 (-2400 1100);
PAINT BLUE (-2400 1100);
FORCEPROP 2 LAST SEC_TYPE 0402LF
J 0
(-2400 1450);
DISPLAY 1.021277 (-2400 1450);
PAINT ORANGE (-2400 1450);
DISPLAY INVISIBLE (-2400 1450);
FORCEPROP 0 LAST SEC 1
J 0
(-2400 1350);
PAINT MONO (-2400 1350);
DISPLAY INVISIBLE (-2400 1350);
FORCEPROP 0 LAST CDS_LOCATION CT4
J 0
(-2400 1350);
PAINT MONO (-2400 1350);
DISPLAY INVISIBLE (-2400 1350);
FORCEPROP 1 LAST PATH I87
J 0
(-2400 1400);
DISPLAY 0.978723 (-2400 1400);
PAINT WHITE (-2400 1400);
DISPLAY INVISIBLE (-2400 1400);
FORCEPROP 0 LAST ROOM VDDQ_KLM_PWR_VR
J 0
(-2400 1450);
DISPLAY 1.021277 (-2400 1450);
PAINT ORANGE (-2400 1450);
DISPLAY INVISIBLE (-2400 1450);
FORCEPROP 2 LAST CDS_LIB mstr_discrete
J 0
(-2450 1250);
PAINT MONO (-2450 1250);
DISPLAY INVISIBLE (-2450 1250);
FORCEADD CAP_A..1
(-1250 3300);
FORCEPROP 0 LAST GROUP PWR_MLCC_CAP
J 0
(-1202 3102);
DISPLAY 0.638298 (-1202 3102);
PAINT BROWN (-1202 3102);
DISPLAY BOTH (-1202 3102);
FORCEPROP 1 LAST VALUE 22.0UF
J 0
(-1200 3400);
DISPLAY 0.617021 (-1200 3400);
PAINT SKYBLUE (-1200 3400);
FORCEPROP 1 LAST PART_NUMBER E15431-004
J 0
(-1200 3200);
DISPLAY 0.617021 (-1200 3200);
PAINT BLUE (-1200 3200);
FORCEPROP 1 LAST PACK_TYPE 0603V
J 0
(-1200 3150);
DISPLAY 0.617021 (-1200 3150);
PAINT SKYBLUE (-1200 3150);
FORCEPROP 1 LAST MATERIAL X6S
J 0
(-1200 3250);
DISPLAY 0.617021 (-1200 3250);
PAINT SKYBLUE (-1200 3250);
FORCEPROP 1 LAST TOLERANCE 20%
J 0
(-1200 3300);
DISPLAY 0.617021 (-1200 3300);
PAINT SKYBLUE (-1200 3300);
FORCEPROP 1 LAST VOLTAGE 4V
J 0
(-1200 3350);
DISPLAY 0.617021 (-1200 3350);
PAINT SKYBLUE (-1200 3350);
FORCEPROP 1 LAST LOCATION C6R7
J 0
(-1200 3450);
DISPLAY 0.617021 (-1200 3450);
PAINT AQUA (-1200 3450);
FORCEPROP 1 LASTPIN (-1250 3200) $PN 2
J 0
(-1240 3180);
DISPLAY 0.617021 (-1240 3180);
PAINT GREEN (-1240 3180);
FORCEPROP 1 LASTPIN (-1250 3400) $PN 1
J 0
(-1240 3380);
DISPLAY 0.617021 (-1240 3380);
PAINT GREEN (-1240 3380);
FORCEPROP 2 LAST CDS_LIB dev_discrete
J 0
(-1250 3300);
PAINT ORANGE (-1250 3300);
DISPLAY INVISIBLE (-1250 3300);
FORCEPROP 2 LAST CDS_LOCATION C6R7
J 0
(-1200 3400);
DISPLAY 0.617021 (-1200 3400);
PAINT AQUA (-1200 3400);
DISPLAY INVISIBLE (-1200 3400);
FORCEPROP 2 LAST ROOM PVCCIN_CPU0_PWR_VR
J 0
(-1200 3450);
DISPLAY 1.446809 (-1200 3450);
PAINT MONO (-1200 3450);
DISPLAY INVISIBLE (-1200 3450);
FORCEPROP 1 LAST PATH I9
J 0
(-1200 3450);
DISPLAY 0.978723 (-1200 3450);
PAINT WHITE (-1200 3450);
DISPLAY INVISIBLE (-1200 3450);
FORCEPROP 2 LAST CDS_SEC 1
J 0
(-1200 3450);
PAINT ORANGE (-1200 3450);
DISPLAY INVISIBLE (-1200 3450);
FORCEPROP 2 LAST BOM_COST PROC_VRD_VCCIN_CPU0
J 0
(-1200 3450);
DISPLAY 1.446809 (-1200 3450);
PAINT MONO (-1200 3450);
DISPLAY INVISIBLE (-1200 3450);
FORCEPROP 2 LAST SEC 1
J 0
(-1195 3500);
DISPLAY 0.680851 (-1195 3500);
PAINT MONO (-1195 3500);
DISPLAY INVISIBLE (-1195 3500);
FORCEPROP 2 LAST SEC_TYPE 0603V
J 0
(-1195 3500);
DISPLAY 1.021277 (-1195 3500);
PAINT ORANGE (-1195 3500);
DISPLAY INVISIBLE (-1195 3500);
FORCEADD CAP..1
(-2550 3325);
FORCEPROP 1 LAST VALUE 1000PF
J 0
(-2500 3375);
DISPLAY 0.617021 (-2500 3375);
PAINT SKYBLUE (-2500 3375);
FORCEPROP 1 LAST PACK_TYPE 0402LF
J 0
(-2350 3275);
DISPLAY 0.617021 (-2350 3275);
PAINT SKYBLUE (-2350 3275);
FORCEPROP 0 LAST POP NOPOP
J 0
(-2350 3325);
DISPLAY 0.808511 (-2350 3325);
PAINT RED (-2350 3325);
FORCEPROP 1 LAST LOCATION CT3
J 0
(-2500 3425);
DISPLAY 0.617021 (-2500 3425);
PAINT AQUA (-2500 3425);
FORCEPROP 1 LASTPIN (-2550 3225) $PN 2
J 0
(-2540 3205);
DISPLAY 0.787234 (-2540 3205);
PAINT ORANGE (-2540 3205);
FORCEPROP 1 LASTPIN (-2550 3425) $PN 1
J 0
(-2540 3405);
DISPLAY 0.787234 (-2540 3405);
PAINT ORANGE (-2540 3405);
FORCEPROP 1 LAST TOLERANCE 10%
J 0
(-2500 3275);
DISPLAY 0.617021 (-2500 3275);
PAINT SKYBLUE (-2500 3275);
FORCEPROP 1 LAST VOLTAGE 50V
J 0
(-2500 3325);
DISPLAY 0.617021 (-2500 3325);
PAINT SKYBLUE (-2500 3325);
FORCEPROP 1 LAST MATERIAL X7R
J 0
(-2325 3375);
DISPLAY 0.617021 (-2325 3375);
PAINT SKYBLUE (-2325 3375);
FORCEPROP 1 LAST PART_NUMBER A36096-046
J 0
(-2350 3425);
DISPLAY 0.617021 (-2350 3425);
PAINT BLUE (-2350 3425);
FORCEPROP 2 LAST CDS_LIB mstr_discrete
J 0
(-2550 3325);
PAINT MONO (-2550 3325);
DISPLAY INVISIBLE (-2550 3325);
FORCEPROP 1 LAST PATH I97
J 0
(-2500 3475);
DISPLAY 0.978723 (-2500 3475);
PAINT WHITE (-2500 3475);
DISPLAY INVISIBLE (-2500 3475);
FORCEPROP 0 LAST ROOM VDDQ_KLM_PWR_VR
J 0
(-2500 3525);
DISPLAY 1.021277 (-2500 3525);
PAINT ORANGE (-2500 3525);
DISPLAY INVISIBLE (-2500 3525);
FORCEPROP 0 LAST SEC 1
J 0
(-2500 3475);
DISPLAY 0.680851 (-2500 3475);
PAINT MONO (-2500 3475);
DISPLAY INVISIBLE (-2500 3475);
FORCEPROP 2 LAST SEC_TYPE 0402LF
J 0
(-2500 3525);
DISPLAY 1.021277 (-2500 3525);
PAINT ORANGE (-2500 3525);
DISPLAY INVISIBLE (-2500 3525);
FORCEADD CAP..1
(-2550 825);
FORCEPROP 1 LAST MATERIAL X7R
J 0
(-2500 800);
DISPLAY 0.617021 (-2500 800);
PAINT SKYBLUE (-2500 800);
FORCEPROP 1 LASTPIN (-2550 925) $PN 1
J 0
(-2540 905);
DISPLAY 0.787234 (-2540 905);
PAINT ORANGE (-2540 905);
FORCEPROP 1 LAST LOCATION CT5
J 0
(-2500 850);
DISPLAY 0.617021 (-2500 850);
PAINT AQUA (-2500 850);
FORCEPROP 0 LAST POP NOPOP
J 0
(-2150 850);
DISPLAY 0.808511 (-2150 850);
PAINT RED (-2150 850);
FORCEPROP 1 LAST VALUE 1000PF
J 0
(-2425 850);
DISPLAY 0.617021 (-2425 850);
PAINT SKYBLUE (-2425 850);
FORCEPROP 1 LAST VOLTAGE 50V
J 0
(-2375 800);
DISPLAY 0.617021 (-2375 800);
PAINT SKYBLUE (-2375 800);
FORCEPROP 1 LAST PACK_TYPE 0402LF
J 0
(-2275 750);
DISPLAY 0.617021 (-2275 750);
PAINT SKYBLUE (-2275 750);
FORCEPROP 1 LAST TOLERANCE 10%
J 0
(-2250 800);
DISPLAY 0.617021 (-2250 800);
PAINT SKYBLUE (-2250 800);
FORCEPROP 1 LASTPIN (-2550 725) $PN 2
J 0
(-2540 705);
DISPLAY 0.787234 (-2540 705);
PAINT ORANGE (-2540 705);
FORCEPROP 1 LAST PART_NUMBER A36096-046
J 0
(-2500 750);
DISPLAY 0.617021 (-2500 750);
PAINT BLUE (-2500 750);
FORCEPROP 2 LAST SEC_TYPE 0402LF
J 0
(-2500 1025);
DISPLAY 1.021277 (-2500 1025);
PAINT ORANGE (-2500 1025);
DISPLAY INVISIBLE (-2500 1025);
FORCEPROP 2 LAST SEC 1
J 0
(-2500 1025);
DISPLAY 0.680851 (-2500 1025);
PAINT MONO (-2500 1025);
DISPLAY INVISIBLE (-2500 1025);
FORCEPROP 1 LAST PATH I98
J 0
(-2500 975);
DISPLAY 0.978723 (-2500 975);
PAINT WHITE (-2500 975);
DISPLAY INVISIBLE (-2500 975);
FORCEPROP 0 LAST ROOM VDDQ_KLM_PWR_VR
J 0
(-2500 1025);
DISPLAY 1.021277 (-2500 1025);
PAINT ORANGE (-2500 1025);
DISPLAY INVISIBLE (-2500 1025);
FORCEPROP 2 LAST CDS_LIB mstr_discrete
J 0
(-2550 825);
PAINT MONO (-2550 825);
DISPLAY INVISIBLE (-2550 825);
FORCEADD DNS..2
(-820 1345);
PAINT RED (-820 1345);
FORCEPROP 2 LAST CDS_LIB mstr_misc
J 0
(-820 1345);
PAINT ORANGE (-820 1345);
DISPLAY INVISIBLE (-820 1345);
FORCEPROP 1 LAST COMMENT_BODY TRUE
R 1
J 0
(-745 1120);
DISPLAY 0.872340 (-745 1120);
PAINT GREEN (-745 1120);
DISPLAY INVISIBLE (-745 1120);
FORCEADD DNS..2
(-745 3895);
PAINT RED (-745 3895);
FORCEPROP 2 LAST CDS_LIB mstr_misc
J 0
(-745 3895);
PAINT ORANGE (-745 3895);
DISPLAY INVISIBLE (-745 3895);
FORCEPROP 1 LAST COMMENT_BODY TRUE
R 1
J 0
(-670 3670);
DISPLAY 0.872340 (-670 3670);
PAINT GREEN (-670 3670);
DISPLAY INVISIBLE (-670 3670);
FORCEADD INTEL_CORP_BPAGE..1
(0 0);
FORCEPROP 1 LAST CDS_CON_LAST_MODIFIED Fri Jun 16 17:49:14 2017
J 0
(-1425 325);
PAINT ORANGE (-1425 325);
DISPLAY INVISIBLE (-1425 325);
FORCEPROP 2 LAST CUSTOM_TXT_CDS <XR_PAGE_TITLE>
J 0
(-7890 5250);
DISPLAY 0.638298 (-7890 5250);
PAINT PINK (-7890 5250);
DISPLAY INVISIBLE (-7890 5250);
FORCEPROP 2 LAST CUSTOM_TXT_CDS <CON_LAST_MODIFIED>
J 0
(-4000 100);
PAINT ORANGE (-4000 100);
FORCEPROP 2 LAST CUSTOM_TXT_CDS <CURRENT_DESIGN_SHEET> OF <TOTAL_DESIGN_SHEETS>
J 0
(-500 25);
PAINT ORANGE (-500 25);
FORCEPROP 1 LAST SCH_TITLE VCCIN CPU0 (2 OF 4)
J 0
(-7950 50);
DISPLAY 1.212766 (-7950 50);
PAINT ORANGE (-7950 50);
FORCEPROP 1 LAST COMMENT_BODY TRUE
J 0
(12 12);
DISPLAY 0.468085 (12 12);
PAINT GREEN (12 12);
DISPLAY INVISIBLE (12 12);
FORCEPROP 2 LAST PAGE_BORDER TRUE
J 0
(-7890 5250);
DISPLAY 0.638298 (-7890 5250);
PAINT PINK (-7890 5250);
DISPLAY INVISIBLE (-7890 5250);
FORCEPROP 2 LAST CDS_LIB mstr_symbols
J 0
(0 0);
PAINT MONO (0 0);
DISPLAY INVISIBLE (0 0);
FORCEPROP 2 LAST CDS_XR_PAGE_TITLE CR-202 : @BASEBOARD_FAB2_LIB.BASEBOARD_FAB2(SCH_1):PAGE202
J 0
(-7890 5250);
DISPLAY 0.638298 (-7890 5250);
PAINT PINK (-7890 5250);
DISPLAY INVISIBLE (-7890 5250);
WIRE 16 -1 (-2800 3175)(-2800 3250);
WIRE 16 -1 (-2800 3250)(-2800 3300);
WIRE 16 -1 (-2800 3250)(-2925 3250);
WIRE 16 -1 (-2800 3300)(-2800 3350);
WIRE 16 -1 (-2800 3300)(-2925 3300);
WIRE 16 -1 (-2800 3350)(-2800 3400);
WIRE 16 -1 (-2800 3350)(-2925 3350);
WIRE 16 -1 (-2925 3400)(-2800 3400);
WIRE 16 -1 (-500 950)(-500 1000);
WIRE 16 -1 (-850 950)(-500 950);
WIRE 16 -1 (-500 850)(-500 950);
WIRE 16 -1 (-950 950)(-850 950);
WIRE 16 -1 (-850 850)(-850 950);
WIRE 16 -1 (-950 325)(-950 950);
WIRE 16 -1 (-950 950)(-1150 950);
WIRE 16 -1 (-4125 325)(-950 325);
WIRE 16 -1 (-4125 1325)(-4125 325);
WIRE 16 -1 (-3975 1325)(-4125 1325);
WIRE 16 -1 (-500 525)(-500 550);
WIRE 16 -1 (-850 550)(-500 550);
WIRE 16 -1 (-500 650)(-500 550);
WIRE 16 -1 (-850 550)(-850 650);
WIRE 16 -1 (-2800 575)(-2800 625);
WIRE 16 -1 (-2800 625)(-2800 675);
WIRE 16 -1 (-2800 625)(-2975 625);
WIRE 16 -1 (-2800 675)(-2800 725);
WIRE 16 -1 (-2800 675)(-2975 675);
WIRE 16 -1 (-2800 725)(-2800 775);
WIRE 16 -1 (-2800 725)(-2975 725);
WIRE 16 -1 (-2975 775)(-2800 775);
WIRE 16 -1 (-650 3500)(-650 3550);
WIRE 16 -1 (-1250 3500)(-650 3500);
WIRE 16 -1 (-650 3400)(-650 3500);
WIRE 16 -1 (-1400 3500)(-1250 3500);
WIRE 16 -1 (-1250 3400)(-1250 3500);
WIRE 16 -1 (-1400 2625)(-1400 3500);
WIRE 16 -1 (-1550 3500)(-1400 3500);
WIRE 16 -1 (-4050 2625)(-1400 2625);
WIRE 16 -1 (-4050 3950)(-4050 2625);
WIRE 16 -1 (-3925 3950)(-4050 3950);
WIRE 16 -1 (-6600 4450)(-6600 4300);
WIRE 16 -1 (-6600 4300)(-6550 4300);
WIRE 16 -1 (-6600 4300)(-6825 4300);
WIRE 16 -1 (-7100 4300)(-6825 4300);
WIRE 16 -1 (-6825 4175)(-6825 4300);
WIRE 16 -1 (-6550 4300)(-6250 4300);
WIRE 16 -1 (-6550 4175)(-6550 4300);
WIRE 16 -1 (-6250 4300)(-5975 4300);
WIRE 16 -1 (-6250 4175)(-6250 4300);
WIRE 16 -1 (-7100 4175)(-7100 4300);
WIRE 16 -1 (-4075 4300)(-5975 4300);
WIRE 16 -1 (-5975 4150)(-5975 4300);
WIRE 16 -1 (-4075 4300)(-4075 4250);
WIRE 16 -1 (-3925 4300)(-4075 4300);
WIRE 16 -1 (-4075 4250)(-3925 4250);
WIRE 16 -1 (-7100 3575)(-7100 3800);
WIRE 16 -1 (-7100 3800)(-6825 3800);
WIRE 16 -1 (-7100 3975)(-7100 3800);
WIRE 16 -1 (-6825 3800)(-6550 3800);
WIRE 16 -1 (-6825 3975)(-6825 3800);
WIRE 16 -1 (-6550 3800)(-6250 3800);
WIRE 16 -1 (-6550 3975)(-6550 3800);
WIRE 16 -1 (-6250 3800)(-5975 3800);
WIRE 16 -1 (-6250 3975)(-6250 3800);
WIRE 16 -1 (-5975 3800)(-5700 3800);
WIRE 16 -1 (-5975 3950)(-5975 3800);
WIRE 16 -1 (-5275 3800)(-5700 3800);
WIRE 16 -1 (-5700 3925)(-5700 3800);
WIRE 16 -1 (-4900 3800)(-5275 3800);
WIRE 16 -1 (-5275 4000)(-5275 3800);
WIRE 16 -1 (-4900 4025)(-4900 3800);
WIRE 16 -1 (-6725 1825)(-6725 1675);
WIRE 16 -1 (-6725 1675)(-6625 1675);
WIRE 16 -1 (-6725 1675)(-6900 1675);
WIRE 16 -1 (-7175 1675)(-6900 1675);
WIRE 16 -1 (-6900 1575)(-6900 1675);
WIRE 16 -1 (-6625 1675)(-6350 1675);
WIRE 16 -1 (-6625 1575)(-6625 1675);
WIRE 16 -1 (-6350 1675)(-6050 1675);
WIRE 16 -1 (-6350 1575)(-6350 1675);
WIRE 16 -1 (-7175 1575)(-7175 1675);
WIRE 16 -1 (-4100 1675)(-6050 1675);
WIRE 16 -1 (-6050 1575)(-6050 1675);
WIRE 16 -1 (-4100 1675)(-4100 1625);
WIRE 16 -1 (-3975 1675)(-4100 1675);
WIRE 16 -1 (-3975 1625)(-4100 1625);
WIRE 16 -1 (-7175 1100)(-7175 1175);
WIRE 16 -1 (-7175 1175)(-6900 1175);
WIRE 16 -1 (-7175 1375)(-7175 1175);
WIRE 16 -1 (-6625 1175)(-6900 1175);
WIRE 16 -1 (-6900 1375)(-6900 1175);
WIRE 16 -1 (-6625 1175)(-6350 1175);
WIRE 16 -1 (-6625 1375)(-6625 1175);
WIRE 16 -1 (-6350 1175)(-6050 1175);
WIRE 16 -1 (-6350 1375)(-6350 1175);
WIRE 16 -1 (-6050 1175)(-5775 1175);
WIRE 16 -1 (-6050 1375)(-6050 1175);
WIRE 16 -1 (-5275 1175)(-5775 1175);
WIRE 16 -1 (-5775 1375)(-5775 1175);
WIRE 16 -1 (-4950 1175)(-5275 1175);
WIRE 16 -1 (-5275 1350)(-5275 1175);
WIRE 16 -1 (-4950 1325)(-4950 1175);
WIRE 16 -1 (-4700 1975)(-4700 2050);
WIRE 16 -1 (-4700 1525)(-4700 1975);
WIRE 16 -1 (-4950 1975)(-4700 1975);
WIRE 16 -1 (-4950 1975)(-5275 1975);
WIRE 16 -1 (-4950 1525)(-4950 1975);
WIRE 16 -1 (-4100 1525)(-4700 1525);
WIRE 16 -1 (-4100 1425)(-4100 1525);
WIRE 16 -1 (-3975 1525)(-4100 1525);
WIRE 16 -1 (-5275 1500)(-5275 1975);
WIRE 16 -1 (-5275 1975)(-5525 1975);
WIRE 16 -1 (-3975 1425)(-4100 1425);
WIRE 16 -1 (-4675 4625)(-4675 4700);
WIRE 16 -1 (-4675 4625)(-4675 4150);
WIRE 16 -1 (-4675 4625)(-4900 4625);
WIRE 16 -1 (-4900 4625)(-5275 4625);
WIRE 16 -1 (-4900 4225)(-4900 4625);
WIRE 16 -1 (-4675 4150)(-4050 4150);
WIRE 16 -1 (-4050 4150)(-4050 4050);
WIRE 16 -1 (-4050 4150)(-3925 4150);
WIRE 16 -1 (-5275 4150)(-5275 4625);
WIRE 16 -1 (-5450 4625)(-5275 4625);
WIRE 16 -1 (-4050 4050)(-3925 4050);
WIRE 16 -1 (-750 3800)(-750 3750);
WIRE 16 -1 (-825 1250)(-825 1200);
WIRE 16 -1 (-4125 3200)(-4125 3100);
WIRE 16 -1 (-2350 3775)(-2350 3675);
WIRE 16 -1 (-2550 2825)(-2550 2800);
WIRE 16 -1 (-650 3075)(-650 3100);
WIRE 16 -1 (-1250 3100)(-650 3100);
WIRE 16 -1 (-650 3200)(-650 3100);
WIRE 16 -1 (-1250 3100)(-1250 3200);
WIRE 16 -1 (-4175 575)(-4175 475);
WIRE 16 -1 (-2450 1150)(-2450 1100);
WIRE 3 2175 (-2750 900)(-1600 900);
WIRE 3 2175 (-1600 900)(-1600 350);
WIRE 3 2175 (-2750 900)(-2750 350);
WIRE 3 2175 (-2750 350)(-1600 350);
WIRE 3 2175 (-2525 1000)(-2050 1000);
WIRE 3 2175 (-2050 1425)(-2050 1000);
WIRE 3 2175 (-2525 1425)(-2525 1000);
WIRE 3 2175 (-2525 1425)(-2050 1425);
WIRE 16 -1 (-2975 950)(-2975 875);
WIRE 16 -1 (-2550 950)(-2975 950);
FORCEPROP 0 LAST VOLTAGE 5
J 0
(-2825 1025);
DISPLAY 1.021277 (-2825 1025);
PAINT SKYBLUE (-2825 1025);
DISPLAY INVISIBLE (-2825 1025);
FORCEPROP 2 LAST SIG_NAME VR_PVCCIN_CPU0_PHASE2
J 0
(-2715 960);
DISPLAY 0.617021 (-2715 960);
PAINT ORANGE (-2715 960);
FORCEPROP 2 LASTPROP $XRERR UNIQUE?
J 0
(-2955 960);
DISPLAY 0.638298 (-2955 960);
PAINT MONO (-2955 960);
DISPLAY INVISIBLE (-2955 960);
WIRE 16 -1 (-2550 925)(-2550 950);
WIRE 16 -1 (-1450 950)(-2550 950);
WIRE 16 -1 (-6675 1075)(-3975 1075);
FORCEPROP 2 LAST SIG_NAME VR_PVCCIN_CPU0_PWM2
J 0
(-6688 1085);
DISPLAY 0.617021 (-6688 1085);
PAINT ORANGE (-6688 1085);
WIRE 16 -1 (-4175 2100)(-1775 2100);
FORCEPROP 2 LAST SIG_NAME VR_PVCCIN_CPU0_AIREF2
J 0
(-2743 2132);
DISPLAY 0.617021 (-2743 2132);
PAINT ORANGE (-2743 2132);
WIRE 16 -1 (-4175 775)(-4175 975);
WIRE 16 -1 (-4175 975)(-4175 2100);
WIRE 16 -1 (-4175 975)(-3975 975);
WIRE 16 -1 (-3975 1175)(-4725 1175);
FORCEPROP 0 LAST SIG_NAME TP_PVCCIN_CPU0_PH2_GL_0
J 0
(-4698 1190);
DISPLAY 0.617021 (-4698 1190);
PAINT ORANGE (-4698 1190);
FORCEPROP 2 LASTPROP $XRERR UNIQUE?
J 0
(-4965 1175);
DISPLAY 0.638298 (-4965 1175);
PAINT MONO (-4965 1175);
DISPLAY INVISIBLE (-4965 1175);
WIRE 16 -1 (-3975 1225)(-4725 1225);
FORCEPROP 0 LAST SIG_NAME TP_PVCCIN_CPU0_PH2_GL_1
J 0
(-4698 1240);
DISPLAY 0.617021 (-4698 1240);
PAINT ORANGE (-4698 1240);
FORCEPROP 2 LASTPROP $XRERR UNIQUE?
J 0
(-4965 1225);
DISPLAY 0.638298 (-4965 1225);
PAINT MONO (-4965 1225);
DISPLAY INVISIBLE (-4965 1225);
WIRE 16 -1 (-4250 825)(-3975 825);
WIRE 16 -1 (-4250 725)(-4250 825);
WIRE 16 -1 (-5950 725)(-4250 725);
FORCEPROP 0 LAST VOLTAGE 5
J 0
(-5925 800);
DISPLAY 1.021277 (-5925 800);
PAINT SKYBLUE (-5925 800);
DISPLAY INVISIBLE (-5925 800);
FORCEPROP 2 LAST SIG_NAME VR_PVCCIN_CPU0_PH2_PHASE
J 0
(-5928 731);
DISPLAY 0.617021 (-5928 731);
PAINT ORANGE (-5928 731);
FORCEPROP 2 LASTPROP $XRERR UNIQUE?
J 0
(-6168 731);
DISPLAY 0.638298 (-6168 731);
PAINT MONO (-6168 731);
DISPLAY INVISIBLE (-6168 731);
WIRE 16 -1 (-5950 950)(-5950 925);
WIRE 16 -1 (-5125 950)(-5950 950);
FORCEPROP 2 LAST SIG_NAME VR_PVCCIN_CPU0_PH2_BOOT
J 0
(-5967 960);
DISPLAY 0.617021 (-5967 960);
PAINT ORANGE (-5967 960);
FORCEPROP 2 LASTPROP $XRERR UNIQUE?
J 0
(-6207 960);
DISPLAY 0.638298 (-6207 960);
PAINT MONO (-6207 960);
DISPLAY INVISIBLE (-6207 960);
WIRE 16 2175 (-6275 575)(-5200 575);
WIRE 16 2175 (-5200 1025)(-5200 575);
WIRE 16 2175 (-6275 1025)(-6275 575);
WIRE 16 2175 (-6275 1025)(-5200 1025);
WIRE 16 2175 (-5500 1600)(-4875 1600);
WIRE 16 2175 (-4875 1600)(-4875 1200);
WIRE 16 2175 (-5500 1600)(-5500 1200);
WIRE 16 2175 (-5500 1200)(-4875 1200);
WIRE 3 682 (-5225 1550)(-5225 1275);
WIRE 3 682 (-5225 1550)(-5325 1550);
WIRE 3 682 (-5225 1275)(-5325 1275);
WIRE 3 682 (-5325 1275)(-5325 1550);
WIRE 16 -1 (-5775 1975)(-5725 1975);
WIRE 16 -1 (-5775 1575)(-5775 1725);
WIRE 16 -1 (-5775 1975)(-5775 1725);
WIRE 16 -1 (-5775 1725)(-3975 1725);
FORCEPROP 0 LAST VOLTAGE 5
J 0
(-4575 1800);
DISPLAY 1.021277 (-4575 1800);
PAINT SKYBLUE (-4575 1800);
DISPLAY INVISIBLE (-4575 1800);
FORCEPROP 2 LAST SIG_NAME VR_PVCCIN_CPU0_PH2_VCIN
J 0
(-5740 1735);
DISPLAY 0.617021 (-5740 1735);
PAINT ORANGE (-5740 1735);
FORCEPROP 2 LASTPROP $XRERR UNIQUE?
J 0
(-5980 1735);
DISPLAY 0.638298 (-5980 1735);
PAINT MONO (-5980 1735);
DISPLAY INVISIBLE (-5980 1735);
WIRE 3 2175 (-5800 1825)(-5325 1825);
WIRE 3 2175 (-5325 2100)(-5325 1825);
WIRE 3 2175 (-5800 2100)(-5800 1825);
WIRE 3 2175 (-5800 2100)(-5325 2100);
WIRE 16 -1 (-3925 3700)(-6650 3700);
WIRE 16 2175 (-6125 3675)(-6125 3225);
WIRE 16 2175 (-6125 3225)(-5425 3225);
WIRE 16 2175 (-6125 3675)(-5425 3675);
WIRE 16 2175 (-5425 3675)(-5425 3225);
WIRE 16 -1 (-4200 3450)(-3925 3450);
WIRE 16 -1 (-4200 3350)(-4200 3450);
WIRE 16 -1 (-5850 3350)(-4200 3350);
FORCEPROP 0 LAST VOLTAGE 5
J 0
(-5800 3425);
DISPLAY 1.021277 (-5800 3425);
PAINT SKYBLUE (-5800 3425);
DISPLAY INVISIBLE (-5800 3425);
FORCEPROP 2 LAST SIG_NAME VR_PVCCIN_CPU0_PH1_PHASE
J 0
(-5815 3360);
DISPLAY 0.617021 (-5815 3360);
PAINT ORANGE (-5815 3360);
FORCEPROP 2 LASTPROP $XRERR UNIQUE?
J 0
(-6055 3360);
DISPLAY 0.638298 (-6055 3360);
PAINT MONO (-6055 3360);
DISPLAY INVISIBLE (-6055 3360);
WIRE 16 -1 (-2975 1725)(-1725 1725);
FORCEPROP 2 LAST SIG_NAME ISENSE_PVCCIN_CPU0_PH2_IMON
J 0
(-2814 1731);
DISPLAY 0.617021 (-2814 1731);
PAINT ORANGE (-2814 1731);
WIRE 16 2175 (-5400 3825)(-4725 3825);
WIRE 16 2175 (-4725 4275)(-4725 3825);
WIRE 16 2175 (-5400 4275)(-5400 3825);
WIRE 16 2175 (-5400 4275)(-4725 4275);
WIRE 16 -1 (-4125 4750)(-1450 4750);
FORCEPROP 2 LAST SIG_NAME VR_PVCCIN_CPU0_AIREF1
J 0
(-2907 4761);
DISPLAY 0.617021 (-2907 4761);
PAINT ORANGE (-2907 4761);
WIRE 16 -1 (-4125 3400)(-4125 3600);
WIRE 16 -1 (-4125 3600)(-4125 4750);
WIRE 16 -1 (-3925 3600)(-4125 3600);
WIRE 16 -1 (-5850 3575)(-5850 3550);
WIRE 16 -1 (-5125 3575)(-5850 3575);
FORCEPROP 2 LAST SIG_NAME VR_PVCCIN_CPU0_PH1_BOOT
J 0
(-5840 3585);
DISPLAY 0.617021 (-5840 3585);
PAINT ORANGE (-5840 3585);
FORCEPROP 2 LASTPROP $XRERR UNIQUE?
J 0
(-6080 3585);
DISPLAY 0.638298 (-6080 3585);
PAINT MONO (-6080 3585);
DISPLAY INVISIBLE (-6080 3585);
WIRE 16 -1 (-4200 3500)(-3925 3500);
WIRE 16 -1 (-4200 3575)(-4200 3500);
WIRE 16 -1 (-4925 3575)(-4200 3575);
FORCEPROP 2 LAST SIG_NAME VR_PVCCIN_CPU0_PH1_BOOT_R
J 0
(-4735 3578);
DISPLAY 0.617021 (-4735 3578);
PAINT ORANGE (-4735 3578);
FORCEPROP 2 LASTPROP $XRERR UNIQUE?
J 0
(-4975 3578);
DISPLAY 0.638298 (-4975 3578);
PAINT MONO (-4975 3578);
DISPLAY INVISIBLE (-4975 3578);
WIRE 16 -1 (-5700 4625)(-5650 4625);
WIRE 16 -1 (-5700 4125)(-5700 4350);
WIRE 16 -1 (-5700 4350)(-5700 4625);
WIRE 16 -1 (-5700 4350)(-3925 4350);
FORCEPROP 0 LAST VOLTAGE 5
J 0
(-4525 4425);
DISPLAY 1.021277 (-4525 4425);
PAINT SKYBLUE (-4525 4425);
DISPLAY INVISIBLE (-4525 4425);
FORCEPROP 2 LAST SIG_NAME VR_PVCCIN_CPU0_PH1_VCIN
J 0
(-5615 4360);
DISPLAY 0.617021 (-5615 4360);
PAINT ORANGE (-5615 4360);
FORCEPROP 2 LASTPROP $XRERR UNIQUE?
J 0
(-5855 4360);
DISPLAY 0.638298 (-5855 4360);
PAINT MONO (-5855 4360);
DISPLAY INVISIBLE (-5855 4360);
WIRE 3 682 (-5225 3925)(-5325 3925);
WIRE 3 682 (-5225 4200)(-5225 3925);
WIRE 3 682 (-5325 3925)(-5325 4200);
WIRE 3 682 (-5325 4200)(-5225 4200);
WIRE 16 -1 (-2925 3500)(-2550 3500);
FORCEPROP 2 LAST SIG_NAME VR_PVCCIN_CPU0_PHASE1
J 0
(-2815 3510);
DISPLAY 0.617021 (-2815 3510);
PAINT ORANGE (-2815 3510);
FORCEPROP 2 LASTPROP $XRERR UNIQUE?
J 0
(-3055 3510);
DISPLAY 0.638298 (-3055 3510);
PAINT MONO (-3055 3510);
DISPLAY INVISIBLE (-3055 3510);
WIRE 16 -1 (-2550 3425)(-2550 3500);
WIRE 16 -1 (-2550 3500)(-1850 3500);
FORCEPROP 0 LAST VOLTAGE 5
J 0
(-2500 3575);
DISPLAY 1.021277 (-2500 3575);
PAINT SKYBLUE (-2500 3575);
DISPLAY INVISIBLE (-2500 3575);
WIRE 3 2175 (-5725 4475)(-5375 4475);
WIRE 3 2175 (-5375 4750)(-5375 4475);
WIRE 3 2175 (-5725 4750)(-5725 4475);
WIRE 3 2175 (-5725 4750)(-5375 4750);
WIRE 3 2175 (-5175 3675)(-4825 3675);
WIRE 3 2175 (-4825 3675)(-4825 3400);
WIRE 3 2175 (-5175 3675)(-5175 3400);
WIRE 3 2175 (-5175 3400)(-4825 3400);
WIRE 3 2175 (-5175 1050)(-4850 1050);
WIRE 3 2175 (-4850 1050)(-4850 775);
WIRE 3 2175 (-5175 1050)(-5175 775);
WIRE 3 2175 (-5175 775)(-4850 775);
WIRE 16 -1 (-2550 650)(-2550 725);
WIRE 16 -1 (-2550 650)(-1775 650);
FORCEPROP 2 LAST SIG_NAME VR_PVCCIN_CPU0_PHASE2_RC
J 0
(-2515 660);
DISPLAY 0.617021 (-2515 660);
PAINT ORANGE (-2515 660);
FORCEPROP 2 LASTPROP $XRERR UNIQUE?
J 0
(-1745 650);
DISPLAY 0.638298 (-1745 650);
PAINT MONO (-1745 650);
DISPLAY INVISIBLE (-1745 650);
WIRE 3 2175 (-2700 3475)(-1925 3475);
WIRE 3 2175 (-1925 3475)(-1925 2725);
WIRE 3 2175 (-2700 3475)(-2700 2725);
WIRE 3 2175 (-2700 2725)(-1925 2725);
WIRE 16 -1 (-2550 3225)(-2550 3200);
WIRE 16 -1 (-2550 3200)(-2550 3075);
WIRE 16 -1 (-2550 3200)(-1775 3200);
FORCEPROP 2 LAST SIG_NAME VR_PVCCIN_CPU0_PHASE1_RC
J 0
(-2440 3210);
DISPLAY 0.617021 (-2440 3210);
PAINT ORANGE (-2440 3210);
FORCEPROP 2 LASTPROP $XRERR UNIQUE?
J 0
(-1745 3200);
DISPLAY 0.638298 (-1745 3200);
PAINT MONO (-1745 3200);
DISPLAY INVISIBLE (-1745 3200);
WIRE 16 -1 (-3925 3850)(-4650 3850);
FORCEPROP 0 LAST SIG_NAME TP_PVCCIN_CPU0_PH1_GL_1
J 0
(-4623 3865);
DISPLAY 0.617021 (-4623 3865);
PAINT ORANGE (-4623 3865);
FORCEPROP 2 LASTPROP $XRERR UNIQUE?
J 0
(-4890 3850);
DISPLAY 0.638298 (-4890 3850);
PAINT MONO (-4890 3850);
DISPLAY INVISIBLE (-4890 3850);
WIRE 3 682 (-2900 1475)(-2800 1475);
WIRE 3 2175 (-2450 3550)(-2075 3550);
WIRE 3 2175 (-2075 4050)(-2075 3550);
WIRE 3 2175 (-2450 4050)(-2450 3550);
WIRE 3 2175 (-2450 4050)(-2075 4050);
WIRE 16 -1 (-2350 3975)(-2350 4000);
WIRE 16 -1 (-1750 4000)(-2350 4000);
WIRE 16 -1 (-2925 4000)(-2925 3850);
WIRE 16 -1 (-2925 4000)(-2350 4000);
FORCEPROP 2 LAST SIG_NAME A_TSENSE_PVCCIN_CPU0
J 0
(-2887 4010);
DISPLAY 0.617021 (-2887 4010);
PAINT ORANGE (-2887 4010);
WIRE 16 -1 (-2925 4350)(-1600 4350);
FORCEPROP 2 LAST SIG_NAME ISENSE_PVCCIN_CPU0_PH1_IMON
J 0
(-2635 4360);
DISPLAY 0.617021 (-2635 4360);
PAINT ORANGE (-2635 4360);
WIRE 16 -1 (-750 4000)(-750 4150);
WIRE 16 -1 (-2925 4150)(-750 4150);
FORCEPROP 2 LAST SIG_NAME VR_PVCCIN_CPU0_PH1_OCSET
J 0
(-2793 4166);
DISPLAY 0.617021 (-2793 4166);
PAINT ORANGE (-2793 4166);
FORCEPROP 2 LASTPROP $XRERR UNIQUE?
J 0
(-3033 4166);
DISPLAY 0.638298 (-3033 4166);
PAINT MONO (-3033 4166);
DISPLAY INVISIBLE (-3033 4166);
WIRE 3 682 (-2750 4100)(-2850 4100);
WIRE 16 -1 (-3925 3800)(-4650 3800);
FORCEPROP 0 LAST SIG_NAME TP_PVCCIN_CPU0_PH1_GL_0
J 0
(-4623 3815);
DISPLAY 0.617021 (-4623 3815);
PAINT ORANGE (-4623 3815);
FORCEPROP 2 LASTPROP $XRERR UNIQUE?
J 0
(-4890 3800);
DISPLAY 0.638298 (-4890 3800);
PAINT MONO (-4890 3800);
DISPLAY INVISIBLE (-4890 3800);
WIRE 16 -1 (-4250 950)(-4925 950);
FORCEPROP 2 LAST SIG_NAME VR_PVCCIN_CPU0_PH2_BOOT_R
J 0
(-4817 960);
DISPLAY 0.617021 (-4817 960);
PAINT ORANGE (-4817 960);
FORCEPROP 2 LASTPROP $XRERR UNIQUE?
J 0
(-5057 960);
DISPLAY 0.638298 (-5057 960);
PAINT MONO (-5057 960);
DISPLAY INVISIBLE (-5057 960);
WIRE 16 -1 (-4250 875)(-4250 950);
WIRE 16 -1 (-3975 875)(-4250 875);
WIRE 16 -1 (-2450 1350)(-2450 1375);
WIRE 16 -1 (-1725 1375)(-2450 1375);
WIRE 16 -1 (-2975 1375)(-2975 1225);
WIRE 16 -1 (-2975 1375)(-2450 1375);
FORCEPROP 2 LAST SIG_NAME A_TSENSE_PVCCIN_CPU0
J 0
(-2964 1387);
DISPLAY 0.617021 (-2964 1387);
PAINT ORANGE (-2964 1387);
WIRE 16 -1 (-825 1525)(-825 1450);
WIRE 16 -1 (-2975 1525)(-825 1525);
FORCEPROP 0 LAST VOLTAGE 3.6
J 0
(-2900 1600);
DISPLAY 1.021277 (-2900 1600);
PAINT SKYBLUE (-2900 1600);
DISPLAY INVISIBLE (-2900 1600);
FORCEPROP 2 LAST SIG_NAME VR_PVCCIN_CPU0_PH2_OCSET
J 0
(-2843 1541);
DISPLAY 0.617021 (-2843 1541);
PAINT ORANGE (-2843 1541);
FORCEPROP 2 LASTPROP $XRERR UNIQUE?
J 0
(-3083 1541);
DISPLAY 0.638298 (-3083 1541);
PAINT MONO (-3083 1541);
DISPLAY INVISIBLE (-3083 1541);
DOT 1 (-850 950);
DOT 1 (-500 550);
DOT 1 (-500 950);
DOT 1 (-950 950);
DOT 1 (-650 3500);
DOT 1 (-650 3100);
DOT 1 (-5275 3800);
DOT 1 (-5275 4625);
DOT 1 (-5275 1175);
DOT 1 (-5275 1975);
DOT 1 (-5775 1725);
DOT 1 (-2800 725);
DOT 1 (-2550 3200);
DOT 1 (-5975 3800);
DOT 1 (-2800 3250);
DOT 1 (-1250 3500);
DOT 1 (-4675 4625);
DOT 1 (-4900 4625);
DOT 1 (-4700 1975);
DOT 1 (-4950 1975);
DOT 1 (-2800 3350);
DOT 1 (-6725 1675);
DOT 1 (-2350 4000);
DOT 1 (-2800 3300);
DOT 1 (-4050 4150);
DOT 1 (-4075 4300);
DOT 1 (-2800 675);
DOT 1 (-2800 625);
DOT 1 (-4125 3600);
DOT 1 (-4100 1525);
DOT 1 (-4175 975);
DOT 1 (-2450 1375);
DOT 1 (-7175 1175);
DOT 1 (-7100 3800);
DOT 1 (-6600 4300);
DOT 1 (-4100 1675);
DOT 1 (-2550 950);
DOT 1 (-6900 1675);
DOT 1 (-6900 1175);
DOT 1 (-6625 1675);
DOT 1 (-6625 1175);
DOT 1 (-5775 1175);
DOT 1 (-6050 1675);
DOT 1 (-6050 1175);
DOT 1 (-6350 1675);
DOT 1 (-6350 1175);
DOT 1 (-5700 3800);
DOT 1 (-5700 4350);
DOT 1 (-6825 4300);
DOT 1 (-6825 3800);
DOT 1 (-6550 4300);
DOT 1 (-6550 3800);
DOT 1 (-6250 4300);
DOT 1 (-6250 3800);
DOT 1 (-5975 4300);
DOT 1 (-2550 3500);
DOT 1 (-1400 3500);
FORCENOTE
TP FAB1 CO-LAY WITH TI PARTS 11/16
(-3400 2550) 0;
DISPLAY LEFT (-3400 2550);
DISPLAY 1.021277 (-3400 2550);
PAINT RED (-3400 2550);
FORCENOTE
PLACE ON TOP
(-5505 1100) 0;
DISPLAY LEFT (-5505 1100);
DISPLAY 1.553191 (-5505 1100);
PAINT PURPLE (-5505 1100);
FORCENOTE
TP FAB1 CHANGE PN 0310
(-5475 1600) 0;
DISPLAY LEFT (-5475 1600);
DISPLAY 1.021277 (-5475 1600);
PAINT RED (-5475 1600);
FORCENOTE
TP FAB1 CHANGE TO 0 OHM 0107
(-5775 2100) 0;
DISPLAY LEFT (-5775 2100);
DISPLAY 0.638298 (-5775 2100);
PAINT RED (-5775 2100);
FORCENOTE
TP FAB1 CO-LAY WITH TI PARTS 11/16
(-5375 3025) 0;
DISPLAY LEFT (-5375 3025);
DISPLAY 0.851064 (-5375 3025);
PAINT RED (-5375 3025);
FORCENOTE
TDA21470
(-3575 4425) 0;
DISPLAY LEFT (-3575 4425);
DISPLAY 1.021277 (-3575 4425);
PAINT SKYBLUE (-3575 4425);
FORCENOTE
TDA21470
(-3650 1800) 0;
DISPLAY LEFT (-3650 1800);
DISPLAY 1.021277 (-3650 1800);
PAINT SKYBLUE (-3650 1800);
FORCENOTE
TP FAB1 CO-LAY WITH TI PARTS 11/16
(-2050 1200) 0;
DISPLAY LEFT (-2050 1200);
DISPLAY 1.021277 (-2050 1200);
PAINT RED (-2050 1200);
FORCENOTE
TP FAB1 CO-LAY WITH TI PARTS 11/16
(-1975 425) 0;
DISPLAY LEFT (-1975 425);
DISPLAY 0.702128 (-1975 425);
PAINT RED (-1975 425);
FORCENOTE
TP FAB1 CHANGE RES TO 1 OHM 0603 0107
(-1975 375) 0;
DISPLAY LEFT (-1975 375);
DISPLAY 0.638298 (-1975 375);
PAINT RED (-1975 375);
FORCENOTE
TP FAB1 CHANGE L4D3 PN 0122
(-1725 1100) 0;
DISPLAY LEFT (-1725 1100);
DISPLAY 1.021277 (-1725 1100);
PAINT RED (-1725 1100);
FORCENOTE
TP FAB1 CO-LAY WITH TI PARTS 11/16
(-2100 3775) 0;
DISPLAY LEFT (-2100 3775);
DISPLAY 1.021277 (-2100 3775);
PAINT RED (-2100 3775);
FORCENOTE
TP FAB1 CHANGE L4E1 PN 0122
(-2050 3600) 0;
DISPLAY LEFT (-2050 3600);
DISPLAY 1.021277 (-2050 3600);
PAINT RED (-2050 3600);
FORCENOTE
TP FAB1 CHANGE RES TO 1 OHM 0603 0107
(-1900 2750) 0;
DISPLAY LEFT (-1900 2750);
DISPLAY 0.638298 (-1900 2750);
PAINT RED (-1900 2750);
FORCENOTE
TP FAB1 ADD NET NAME 12/04
(-1900 2800) 0;
DISPLAY LEFT (-1900 2800);
DISPLAY 0.680851 (-1900 2800);
PAINT RED (-1900 2800);
FORCENOTE
TP FAB1 CHANGE PN 0310
(-5425 4300) 0;
DISPLAY LEFT (-5425 4300);
DISPLAY 1.021277 (-5425 4300);
PAINT RED (-5425 4300);
FORCENOTE
PLACE ON TOP
(-5405 3725) 0;
DISPLAY LEFT (-5405 3725);
DISPLAY 1.553191 (-5405 3725);
PAINT PURPLE (-5405 3725);
FORCENOTE
TP FAB1 ADD NET NAME 12/04
(-1825 600) 0;
DISPLAY LEFT (-1825 600);
DISPLAY 0.638298 (-1825 600);
PAINT RED (-1825 600);
FORCENOTE
TP FAB1 CHANGE TO 0 OHM 0107
(-5700 4775) 0;
DISPLAY LEFT (-5700 4775);
DISPLAY 0.638298 (-5700 4775);
PAINT RED (-5700 4775);
FORCENOTE
TP FAB1 DEL NET 0309
(-2725 4075) 0;
DISPLAY LEFT (-2725 4075);
DISPLAY 1.021277 (-2725 4075);
PAINT RED (-2725 4075);
FORCENOTE
SPOF
(-6030 3125) 0;
DISPLAY LEFT (-6030 3125);
DISPLAY 1.936170 (-6030 3125);
PAINT PURPLE (-6030 3125);
FORCENOTE
SPOF
(-6005 575) 0;
DISPLAY LEFT (-6005 575);
DISPLAY 1.808511 (-6005 575);
PAINT PURPLE (-6005 575);
FORCENOTE
ROOM=PVCCIN_CPU0_PWR_VR
(-7880 185) 0;
DISPLAY LEFT (-7880 185);
DISPLAY 2.446809 (-7880 185);
PAINT PURPLE (-7880 185);
FORCENOTE
TP FAB1 CO-LAY WITH TI PARTS 11/16
(-5300 500) 0;
DISPLAY LEFT (-5300 500);
DISPLAY 0.851064 (-5300 500);
PAINT RED (-5300 500);
FORCENOTE
TP FAB1 DEL NET 0309
(-2775 1450) 0;
DISPLAY LEFT (-2775 1450);
DISPLAY 1.021277 (-2775 1450);
PAINT RED (-2775 1450);
QUIT
